G04*
G04 #@! TF.GenerationSoftware,Altium Limited,Altium Designer,23.7.1 (13)*
G04*
G04 Layer_Physical_Order=3*
G04 Layer_Color=16440176*
%FSLAX25Y25*%
%MOIN*%
G70*
G04*
G04 #@! TF.SameCoordinates,AF00DCEB-AC48-4C7C-91EA-99F42E284231*
G04*
G04*
G04 #@! TF.FilePolarity,Positive*
G04*
G01*
G75*
%ADD11C,0.02000*%
%ADD16C,0.00500*%
%ADD17C,0.01500*%
%ADD18C,0.01000*%
%ADD25C,0.00800*%
%ADD217C,0.06299*%
%ADD231C,0.03000*%
%ADD232C,0.04000*%
%ADD233C,0.05000*%
%ADD237R,0.06102X0.06102*%
%ADD244C,0.10000*%
%ADD249C,0.05906*%
%ADD250C,0.01600*%
%ADD252C,0.00500*%
G36*
X299213Y-61024D02*
X175611D01*
Y-102362D01*
X169012D01*
X168468Y-102137D01*
X167752D01*
X167209Y-102362D01*
X155512D01*
Y-81534D01*
X151586D01*
X151257Y-81034D01*
X151406Y-80673D01*
Y-79957D01*
X151132Y-79295D01*
X150626Y-78789D01*
X149964Y-78515D01*
X149248D01*
X148587Y-78789D01*
X148080Y-79295D01*
X147806Y-79957D01*
Y-80673D01*
X147956Y-81034D01*
X147626Y-81534D01*
X146074D01*
X145745Y-81034D01*
X145895Y-80673D01*
Y-79957D01*
X145621Y-79295D01*
X145114Y-78789D01*
X144453Y-78515D01*
X143736D01*
X143075Y-78789D01*
X142569Y-79295D01*
X142295Y-79957D01*
Y-80673D01*
X142444Y-81034D01*
X142114Y-81534D01*
X114567D01*
Y-69291D01*
X81890D01*
Y-44834D01*
X82284D01*
Y-44094D01*
X82284Y-44094D01*
X81890Y-43996D01*
Y-29921D01*
X98570D01*
X98594Y-29957D01*
Y-30673D01*
X98868Y-31335D01*
X99374Y-31841D01*
X100036Y-32115D01*
X100752D01*
X101413Y-31841D01*
X101920Y-31335D01*
X102194Y-30673D01*
Y-29957D01*
X102217Y-29921D01*
X119976D01*
X120183Y-30421D01*
X120128Y-30476D01*
X119853Y-31138D01*
Y-31854D01*
X120128Y-32516D01*
X120634Y-33022D01*
X121295Y-33296D01*
X122012D01*
X122673Y-33022D01*
X123179Y-32516D01*
X123453Y-31854D01*
Y-31138D01*
X123179Y-30476D01*
X123124Y-30421D01*
X123331Y-29921D01*
X167274D01*
X167383Y-30151D01*
X167427Y-30421D01*
X166978Y-30870D01*
X166704Y-31532D01*
Y-32248D01*
X166978Y-32909D01*
X167484Y-33416D01*
X168146Y-33690D01*
X168862D01*
X169524Y-33416D01*
X170030Y-32909D01*
X170304Y-32248D01*
Y-31532D01*
X170030Y-30870D01*
X169581Y-30421D01*
X169625Y-30151D01*
X169734Y-29921D01*
X299213D01*
Y-61024D01*
D02*
G37*
G36*
X-3150Y-24928D02*
Y-34646D01*
X3150Y-40945D01*
X38189D01*
X38611Y-41367D01*
X38328Y-41791D01*
X37760Y-41555D01*
X37043D01*
X36382Y-41829D01*
X35876Y-42336D01*
X35602Y-42997D01*
Y-43713D01*
X35876Y-44375D01*
X36382Y-44881D01*
X37043Y-45155D01*
X37760D01*
X38421Y-44881D01*
X38476Y-44826D01*
X38976Y-45033D01*
Y-46397D01*
X38740Y-46555D01*
X38024D01*
X37362Y-46829D01*
X36856Y-47336D01*
X36582Y-47997D01*
Y-48713D01*
X36856Y-49375D01*
X37362Y-49881D01*
X38024Y-50155D01*
X38740D01*
X38976Y-50313D01*
Y-51552D01*
X38971Y-51555D01*
X38255D01*
X37593Y-51829D01*
X37087Y-52336D01*
X36813Y-52997D01*
Y-53713D01*
X37087Y-54375D01*
X37593Y-54881D01*
X38255Y-55155D01*
X38971D01*
X39632Y-54881D01*
X40139Y-54375D01*
X40413Y-53713D01*
Y-53664D01*
X40875Y-53473D01*
X86187Y-98785D01*
X85995Y-99248D01*
Y-99964D01*
X86269Y-100626D01*
X86726Y-101083D01*
Y-106553D01*
X86226Y-106761D01*
X86001Y-106535D01*
X85339Y-106261D01*
X84623D01*
X83962Y-106535D01*
X83455Y-107041D01*
X83243Y-107554D01*
X82719D01*
X82507Y-107041D01*
X82001Y-106535D01*
X81339Y-106261D01*
X80623D01*
X79962Y-106535D01*
X79455Y-107041D01*
X79181Y-107703D01*
Y-108229D01*
X78560D01*
X77899Y-108504D01*
X77392Y-109010D01*
X77118Y-109671D01*
Y-110388D01*
X77392Y-111049D01*
X77899Y-111556D01*
X78560Y-111829D01*
X79276D01*
X79938Y-111556D01*
X80444Y-111049D01*
X80656Y-110537D01*
X81180D01*
X81392Y-111049D01*
X81899Y-111556D01*
X82560Y-111829D01*
X83276D01*
X83938Y-111556D01*
X84444Y-111049D01*
X84718Y-110388D01*
X85181D01*
X85455Y-111049D01*
X85962Y-111556D01*
X86623Y-111829D01*
X87339D01*
X88001Y-111556D01*
X88507Y-111049D01*
X88781Y-110388D01*
X89244Y-110419D01*
X89518Y-111081D01*
X90025Y-111587D01*
X90686Y-111861D01*
X91402D01*
X92064Y-111587D01*
X92570Y-111081D01*
X92844Y-110419D01*
Y-109703D01*
X92570Y-109041D01*
X92064Y-108535D01*
X91675Y-108374D01*
X91775Y-107874D01*
X156483D01*
X156742Y-108500D01*
X157248Y-109006D01*
X157910Y-109280D01*
X158626D01*
X159287Y-109006D01*
X159516Y-108778D01*
X159843Y-108536D01*
X160169Y-108778D01*
X160398Y-109006D01*
X161059Y-109280D01*
X161775D01*
X162437Y-109006D01*
X162943Y-108500D01*
X163203Y-107874D01*
X212551D01*
X212647Y-108106D01*
X213154Y-108613D01*
X213815Y-108887D01*
X214531D01*
X215193Y-108613D01*
X215699Y-108106D01*
X215973Y-107445D01*
Y-106861D01*
X220079Y-102756D01*
X256395D01*
X270276Y-91244D01*
Y-77953D01*
X301409D01*
Y-59449D01*
X390551D01*
Y-74016D01*
X405905D01*
Y-124362D01*
X405673Y-124458D01*
X405167Y-124965D01*
X404893Y-125626D01*
Y-126342D01*
X405167Y-127004D01*
X405673Y-127510D01*
X405905Y-127606D01*
Y-128740D01*
X402599D01*
X402392Y-128240D01*
X402510Y-128122D01*
X402784Y-127460D01*
Y-126744D01*
X402510Y-126082D01*
X402004Y-125576D01*
X401342Y-125302D01*
X400626D01*
X399965Y-125576D01*
X399458Y-126082D01*
X399184Y-126744D01*
Y-127460D01*
X399458Y-128122D01*
X399577Y-128240D01*
X399370Y-128740D01*
X384883D01*
Y-128146D01*
X384609Y-127484D01*
X384102Y-126978D01*
X383441Y-126704D01*
X382724D01*
X382063Y-126978D01*
X381557Y-127484D01*
X381283Y-128146D01*
Y-128740D01*
X341339D01*
Y-113386D01*
X322162D01*
X321618Y-113161D01*
X320902D01*
X320358Y-113386D01*
X318225D01*
X317681Y-113161D01*
X316965D01*
X316421Y-113386D01*
X304724D01*
Y-157036D01*
X300590Y-161171D01*
X279528D01*
X279528Y-161171D01*
X278981Y-161280D01*
X278518Y-161589D01*
X278518Y-161589D01*
X277509Y-162598D01*
X270276D01*
Y-125591D01*
X263047D01*
Y-123622D01*
X262969Y-123232D01*
X262748Y-122901D01*
X262418Y-122680D01*
X262027Y-122602D01*
X248031D01*
X247641Y-122680D01*
X247310Y-122901D01*
X247090Y-123232D01*
X247012Y-123622D01*
Y-125591D01*
X245669D01*
X239355Y-131904D01*
X223032D01*
X222767Y-131852D01*
X222767Y-131852D01*
X196642D01*
X196377Y-131904D01*
X191148D01*
X191009Y-131697D01*
Y-130981D01*
X190735Y-130319D01*
X190229Y-129813D01*
X189567Y-129539D01*
X188851D01*
X188189Y-129813D01*
X187683Y-130319D01*
X187409Y-130981D01*
Y-131697D01*
X187579Y-132106D01*
X186079Y-133606D01*
X185827Y-133710D01*
X185321Y-134217D01*
X185217Y-134468D01*
X182018Y-137667D01*
X180229D01*
X179951Y-137251D01*
X179985Y-137169D01*
Y-136453D01*
X179711Y-135791D01*
X179483Y-135563D01*
X179241Y-135236D01*
X179483Y-134910D01*
X179711Y-134681D01*
X179985Y-134019D01*
Y-133303D01*
X179711Y-132642D01*
X179205Y-132135D01*
X178544Y-131861D01*
X177828D01*
X177166Y-132135D01*
X176660Y-132642D01*
X176385Y-133303D01*
Y-134019D01*
X176660Y-134681D01*
X176888Y-134910D01*
X177130Y-135236D01*
X176888Y-135563D01*
X176660Y-135791D01*
X176385Y-136453D01*
Y-137169D01*
X176420Y-137251D01*
X176142Y-137667D01*
X174324D01*
X174200Y-137366D01*
X173693Y-136860D01*
X173032Y-136586D01*
X172316D01*
X171654Y-136860D01*
X171148Y-137366D01*
X171023Y-137667D01*
X153677D01*
X153608Y-137563D01*
Y-136847D01*
X153333Y-136185D01*
X152827Y-135679D01*
X152166Y-135405D01*
X151450D01*
X150788Y-135679D01*
X150282Y-136185D01*
X150008Y-136847D01*
Y-137563D01*
X149938Y-137667D01*
X131118D01*
X130784Y-137167D01*
X130863Y-136976D01*
Y-136260D01*
X130589Y-135598D01*
X130083Y-135092D01*
X129421Y-134818D01*
X128705D01*
X128044Y-135092D01*
X128018Y-135117D01*
X127833Y-135204D01*
X127327Y-134698D01*
X126665Y-134424D01*
X125949D01*
X125288Y-134698D01*
X124782Y-135204D01*
X124507Y-135866D01*
Y-136582D01*
X124750Y-137167D01*
X124552Y-137667D01*
X92844D01*
Y-137578D01*
X92570Y-136916D01*
X92064Y-136410D01*
X91402Y-136136D01*
X90686D01*
X90025Y-136410D01*
X89518Y-136916D01*
X89306Y-137428D01*
X88782D01*
X88570Y-136916D01*
X88064Y-136410D01*
X87402Y-136136D01*
X86686D01*
X86025Y-136410D01*
X85518Y-136916D01*
X85306Y-137428D01*
X84782D01*
X84570Y-136916D01*
X84064Y-136410D01*
X83402Y-136136D01*
X82686D01*
X82025Y-136410D01*
X81518Y-136916D01*
X81306Y-137428D01*
X80782D01*
X80570Y-136916D01*
X80064Y-136410D01*
X79402Y-136136D01*
X78686D01*
X78025Y-136410D01*
X77518Y-136916D01*
X77244Y-137578D01*
Y-137667D01*
X72973D01*
X72728Y-137075D01*
X72221Y-136569D01*
X71560Y-136295D01*
X70844D01*
X70429Y-136467D01*
X70415Y-136434D01*
X69909Y-135927D01*
X69247Y-135653D01*
X68531D01*
X67870Y-135927D01*
X67363Y-136434D01*
X67089Y-137095D01*
Y-137667D01*
X62077D01*
X52560Y-128150D01*
X52813Y-127897D01*
X53087Y-127236D01*
Y-126520D01*
X52813Y-125858D01*
X52307Y-125352D01*
X51645Y-125078D01*
X50929D01*
X50267Y-125352D01*
X50169Y-125450D01*
X49860D01*
X-20472Y-55118D01*
Y-20079D01*
X-19944Y-19551D01*
X-8527D01*
X-3150Y-24928D01*
D02*
G37*
G36*
X114173Y-3495D02*
X166058D01*
X166336Y-3911D01*
X166310Y-3973D01*
Y-4689D01*
X166584Y-5350D01*
X166737Y-5503D01*
X166473Y-6138D01*
Y-6854D01*
X166747Y-7516D01*
X167254Y-8022D01*
X167915Y-8296D01*
X168631D01*
X169293Y-8022D01*
X169799Y-7516D01*
X170073Y-6854D01*
Y-6138D01*
X169799Y-5476D01*
X169647Y-5324D01*
X169910Y-4689D01*
Y-3973D01*
X169885Y-3911D01*
X170162Y-3495D01*
X193361D01*
X194336Y-3756D01*
X195428D01*
X196402Y-3495D01*
X207649D01*
Y-3901D01*
X207787Y-4234D01*
X207529Y-4492D01*
X207255Y-5154D01*
Y-5870D01*
X207515Y-6496D01*
X207255Y-7122D01*
Y-7838D01*
X207529Y-8500D01*
X208035Y-9006D01*
X208697Y-9280D01*
X209413D01*
X210075Y-9006D01*
X210581Y-8500D01*
X210855Y-7838D01*
Y-7122D01*
X210596Y-6496D01*
X210855Y-5870D01*
Y-5154D01*
X210717Y-4821D01*
X210975Y-4563D01*
X211249Y-3901D01*
Y-3495D01*
X521260D01*
Y-55118D01*
X481496D01*
Y-25271D01*
X426453D01*
X425889Y-25181D01*
X423717D01*
X423153Y-25271D01*
X355685D01*
X355121Y-25181D01*
X352950D01*
X352385Y-25271D01*
X339764D01*
Y-27559D01*
X170182D01*
X169975Y-27059D01*
X170030Y-27004D01*
X170304Y-26342D01*
Y-25626D01*
X170030Y-24965D01*
X169524Y-24458D01*
X168862Y-24184D01*
X168146D01*
X167484Y-24458D01*
X166978Y-24965D01*
X166704Y-25626D01*
Y-26342D01*
X166978Y-27004D01*
X167033Y-27059D01*
X166826Y-27559D01*
X163095D01*
X162888Y-27059D01*
X162943Y-27004D01*
X163217Y-26342D01*
Y-25626D01*
X162943Y-24965D01*
X162437Y-24458D01*
X161775Y-24184D01*
X161059D01*
X160398Y-24458D01*
X159891Y-24965D01*
X159617Y-25626D01*
Y-26342D01*
X159891Y-27004D01*
X159947Y-27059D01*
X159739Y-27559D01*
X157054D01*
X156847Y-27059D01*
X156854Y-27053D01*
X157128Y-26391D01*
Y-25675D01*
X156854Y-25013D01*
X156347Y-24507D01*
X155686Y-24233D01*
X154970D01*
X154308Y-24507D01*
X153802Y-25013D01*
X153528Y-25675D01*
Y-26391D01*
X153802Y-27053D01*
X153808Y-27059D01*
X153601Y-27559D01*
X124266D01*
X124059Y-27059D01*
X124065Y-27053D01*
X124339Y-26391D01*
Y-25675D01*
X124065Y-25013D01*
X123559Y-24507D01*
X122897Y-24233D01*
X122181D01*
X121519Y-24507D01*
X121013Y-25013D01*
X120739Y-25675D01*
Y-26391D01*
X121013Y-27053D01*
X121019Y-27059D01*
X120812Y-27559D01*
X108493D01*
Y-27201D01*
X108219Y-26539D01*
X107712Y-26033D01*
X107051Y-25759D01*
X106335D01*
X105673Y-26033D01*
X105167Y-26539D01*
X104893Y-27201D01*
Y-27559D01*
X58380D01*
Y-31594D01*
X35829D01*
Y-16535D01*
X43307D01*
Y19291D01*
X114173D01*
Y-3495D01*
D02*
G37*
G36*
X626378Y-162338D02*
X625878Y-162545D01*
X625705Y-162372D01*
X625043Y-162098D01*
X624327D01*
X623665Y-162372D01*
X623159Y-162878D01*
X622885Y-163540D01*
Y-164256D01*
X623159Y-164917D01*
X623665Y-165424D01*
X624327Y-165698D01*
X625043D01*
X625705Y-165424D01*
X625878Y-165250D01*
X626378Y-165457D01*
Y-171998D01*
X625878Y-172280D01*
X625437Y-172098D01*
X624721D01*
X624059Y-172372D01*
X623553Y-172878D01*
X623279Y-173540D01*
Y-174256D01*
X623553Y-174917D01*
X624059Y-175424D01*
X624721Y-175698D01*
X625437D01*
X625878Y-175515D01*
X626378Y-175797D01*
Y-194614D01*
X625878Y-194814D01*
X625296Y-194573D01*
X624580D01*
X623918Y-194847D01*
X623412Y-195353D01*
X623138Y-196015D01*
Y-196731D01*
X623412Y-197393D01*
X623918Y-197899D01*
X624580Y-198173D01*
X625296D01*
X625878Y-197932D01*
X626378Y-198132D01*
Y-199606D01*
X625878Y-199799D01*
X625284Y-199553D01*
X624568D01*
X623907Y-199827D01*
X623400Y-200334D01*
X623126Y-200995D01*
Y-201711D01*
X623400Y-202373D01*
X623907Y-202879D01*
X624568Y-203153D01*
X625284D01*
X625878Y-202907D01*
X626378Y-203100D01*
Y-204614D01*
X625878Y-204814D01*
X625296Y-204573D01*
X624580D01*
X623918Y-204847D01*
X623412Y-205353D01*
X623138Y-206015D01*
Y-206731D01*
X623412Y-207393D01*
X623918Y-207899D01*
X624580Y-208173D01*
X625296D01*
X625878Y-207932D01*
X626378Y-208132D01*
Y-209614D01*
X625878Y-209803D01*
X625276Y-209553D01*
X624560D01*
X623899Y-209827D01*
X623392Y-210334D01*
X623118Y-210995D01*
Y-211711D01*
X623392Y-212373D01*
X623899Y-212879D01*
X624560Y-213153D01*
X625276D01*
X625878Y-212904D01*
X626378Y-213092D01*
Y-226651D01*
X625968Y-226820D01*
X625461Y-227327D01*
X625187Y-227988D01*
Y-228705D01*
X625461Y-229366D01*
X625968Y-229872D01*
X626378Y-230042D01*
Y-232799D01*
X624697Y-234480D01*
X624361Y-234413D01*
X623854Y-233907D01*
X623193Y-233633D01*
X622477D01*
X621815Y-233907D01*
X621309Y-234414D01*
X621035Y-235075D01*
Y-235791D01*
X621309Y-236453D01*
X621815Y-236959D01*
X621882Y-237295D01*
X607336Y-251841D01*
X606846Y-251743D01*
X606843Y-251736D01*
X606337Y-251230D01*
X605675Y-250956D01*
X604959D01*
X604297Y-251230D01*
X603791Y-251736D01*
X603517Y-252398D01*
Y-253114D01*
X603791Y-253776D01*
X604297Y-254282D01*
X604810Y-254494D01*
X604852Y-255018D01*
X604492Y-255167D01*
X603986Y-255673D01*
X603712Y-256335D01*
Y-257051D01*
X603986Y-257713D01*
X604492Y-258219D01*
X605154Y-258493D01*
X605181D01*
Y-259224D01*
X605154D01*
X604492Y-259498D01*
X603986Y-260004D01*
X603712Y-260666D01*
Y-261382D01*
X603986Y-262043D01*
X604492Y-262550D01*
X605154Y-262824D01*
X605181D01*
Y-269746D01*
X604886Y-270459D01*
X604781Y-271260D01*
X604886Y-272060D01*
X605069Y-272503D01*
X604758Y-273003D01*
X604366D01*
X603705Y-273277D01*
X603198Y-273783D01*
X602924Y-274445D01*
Y-275161D01*
X603198Y-275823D01*
X603705Y-276329D01*
X604366Y-276603D01*
X605082D01*
X605181Y-276669D01*
Y-287266D01*
X604886Y-287979D01*
X604781Y-288779D01*
X604886Y-289580D01*
X605181Y-290293D01*
Y-328803D01*
X609449Y-333071D01*
Y-358268D01*
X610236Y-359055D01*
X607480Y-361811D01*
X406299D01*
Y-346063D01*
X414961Y-337402D01*
X444935D01*
X451756Y-344222D01*
X533774D01*
X534108Y-344722D01*
X534027Y-344917D01*
Y-345634D01*
X534301Y-346295D01*
X534807Y-346801D01*
X535469Y-347076D01*
X536185D01*
X536846Y-346801D01*
X537353Y-346295D01*
X537627Y-345634D01*
Y-344917D01*
X537546Y-344722D01*
X537880Y-344222D01*
X567221D01*
Y-320585D01*
X567721Y-320378D01*
X567878Y-320535D01*
X568540Y-320809D01*
X569256D01*
X569917Y-320535D01*
X570424Y-320029D01*
X570698Y-319367D01*
Y-318651D01*
X570424Y-317990D01*
X569917Y-317483D01*
X569256Y-317209D01*
X568540D01*
X567878Y-317483D01*
X567721Y-317640D01*
X567221Y-317433D01*
Y-305699D01*
X569685D01*
X570660Y-305505D01*
X571487Y-304952D01*
X572040Y-304125D01*
X572234Y-303150D01*
X572040Y-302174D01*
X571487Y-301347D01*
X570660Y-300795D01*
X569685Y-300601D01*
X567221D01*
Y-299766D01*
X567637Y-299488D01*
X567752Y-299536D01*
X568468D01*
X569130Y-299262D01*
X569291Y-299101D01*
X569453Y-299262D01*
X570114Y-299536D01*
X570830D01*
X571492Y-299262D01*
X571998Y-298756D01*
X572272Y-298094D01*
Y-297378D01*
X571998Y-296717D01*
X571492Y-296210D01*
X570830Y-295936D01*
X570114D01*
X569453Y-296210D01*
X569291Y-296372D01*
X569130Y-296210D01*
X568468Y-295936D01*
X567752D01*
X567637Y-295984D01*
X567221Y-295706D01*
Y-288905D01*
X579944D01*
X580253Y-289405D01*
X580090Y-289799D01*
Y-290515D01*
X580364Y-291177D01*
X580870Y-291683D01*
X581532Y-291957D01*
X582248D01*
X582909Y-291683D01*
X583416Y-291177D01*
X583690Y-290515D01*
Y-289799D01*
X583416Y-289138D01*
X583071Y-288793D01*
Y-277444D01*
X583457Y-277186D01*
X584173D01*
X584834Y-276912D01*
X585341Y-276405D01*
X585615Y-275744D01*
Y-275028D01*
X585444Y-274615D01*
X586059Y-274361D01*
X586565Y-273854D01*
X586839Y-273193D01*
Y-272477D01*
X586565Y-271815D01*
X586059Y-271309D01*
X585397Y-271035D01*
X584681D01*
X584020Y-271309D01*
X583571Y-271758D01*
X583300Y-271714D01*
X583071Y-271604D01*
Y-237290D01*
X583416Y-236945D01*
X583690Y-236283D01*
Y-235567D01*
X583416Y-234906D01*
X583071Y-234561D01*
Y-226875D01*
X583571Y-226668D01*
X583626Y-226723D01*
X584288Y-226997D01*
X585004D01*
X585665Y-226723D01*
X586172Y-226217D01*
X586446Y-225555D01*
Y-224839D01*
X586172Y-224177D01*
X585665Y-223671D01*
X585004Y-223397D01*
X584288D01*
X583626Y-223671D01*
X583571Y-223726D01*
X583071Y-223519D01*
Y-195605D01*
X579704Y-192237D01*
X579682Y-192130D01*
X579461Y-191799D01*
X579130Y-191578D01*
X579023Y-191556D01*
X577230Y-189764D01*
X541726D01*
Y-181896D01*
X541339Y-151181D01*
X594488Y-98032D01*
Y-81993D01*
X594904Y-81716D01*
X594918Y-81721D01*
X595634D01*
X596295Y-81447D01*
X596802Y-80941D01*
X597076Y-80279D01*
Y-79563D01*
X596802Y-78902D01*
X596295Y-78395D01*
X595634Y-78121D01*
X594918D01*
X594904Y-78127D01*
X594488Y-77849D01*
Y-70472D01*
X608957Y-56004D01*
X626378D01*
Y-162338D01*
D02*
G37*
G36*
X250000Y-67716D02*
Y-83858D01*
X201575D01*
Y-62598D01*
X250000D01*
Y-67716D01*
D02*
G37*
G36*
X605118Y-42913D02*
X558661D01*
Y-81102D01*
X540535Y-99229D01*
X539057Y-98749D01*
X536912Y-98409D01*
X534741D01*
X532596Y-98749D01*
X530531Y-99420D01*
X528596Y-100406D01*
X526840Y-101682D01*
X525304Y-103218D01*
X524028Y-104974D01*
X523042Y-106909D01*
X522371Y-108974D01*
X522031Y-111119D01*
Y-113290D01*
X522371Y-115435D01*
X522851Y-116912D01*
X496288Y-143476D01*
X495705D01*
X495043Y-143750D01*
X494537Y-144256D01*
X494263Y-144918D01*
Y-145393D01*
X493994Y-145616D01*
X493532Y-145356D01*
Y-144918D01*
X493258Y-144256D01*
X492752Y-143750D01*
X492090Y-143476D01*
X491374D01*
X490713Y-143750D01*
X490206Y-144256D01*
X489932Y-144918D01*
Y-145634D01*
X490206Y-146295D01*
X490713Y-146801D01*
X491128Y-146974D01*
Y-147515D01*
X490713Y-147687D01*
X490206Y-148193D01*
X489932Y-148855D01*
Y-149571D01*
X490009Y-149755D01*
X466929Y-172835D01*
Y-228740D01*
X461964Y-233705D01*
Y-246826D01*
X461927Y-246864D01*
X461653Y-247525D01*
Y-248241D01*
X461927Y-248903D01*
X461964Y-248940D01*
Y-253318D01*
X461847D01*
X461185Y-253592D01*
X460679Y-254099D01*
X460405Y-254760D01*
Y-255476D01*
X460679Y-256138D01*
X461185Y-256644D01*
X461847Y-256918D01*
X461964D01*
Y-273649D01*
X452946Y-282667D01*
X452693Y-282414D01*
X452032Y-282140D01*
X451315D01*
X450654Y-282414D01*
X450148Y-282920D01*
X449873Y-283582D01*
Y-284298D01*
X450148Y-284959D01*
X450654Y-285466D01*
X451315Y-285740D01*
X451687D01*
Y-315581D01*
X451326Y-315928D01*
X255118Y-307874D01*
X154724D01*
Y-342126D01*
X163386D01*
Y-362992D01*
X107480D01*
Y-270472D01*
X275179D01*
X375590Y-288976D01*
X417822Y-246745D01*
X417878Y-246801D01*
X418540Y-247076D01*
X419256D01*
X419917Y-246801D01*
X420424Y-246295D01*
X420698Y-245634D01*
Y-244917D01*
X420424Y-244256D01*
X420367Y-244200D01*
X422677Y-241890D01*
Y-207032D01*
X423177Y-206825D01*
X423390Y-207038D01*
X424051Y-207312D01*
X424767D01*
X425429Y-207038D01*
X425691Y-206776D01*
X426259Y-206915D01*
X426427Y-207319D01*
X426933Y-207825D01*
X427595Y-208099D01*
X428311D01*
X428972Y-207825D01*
X429479Y-207319D01*
X429753Y-206657D01*
Y-205941D01*
X429479Y-205280D01*
X428972Y-204773D01*
X428311Y-204499D01*
X427595D01*
X426933Y-204773D01*
X426671Y-205035D01*
X426103Y-204896D01*
X425935Y-204492D01*
X425429Y-203986D01*
X424767Y-203712D01*
X424051D01*
X423390Y-203986D01*
X423177Y-204199D01*
X422677Y-203991D01*
Y-175966D01*
X422839Y-175804D01*
X423113Y-175142D01*
Y-174426D01*
X422839Y-173765D01*
X422677Y-173603D01*
Y-168084D01*
X423193D01*
X423854Y-167810D01*
X424361Y-167304D01*
X424635Y-166642D01*
Y-165926D01*
X424361Y-165265D01*
X423854Y-164758D01*
X423692Y-164691D01*
X423595Y-164201D01*
X434511Y-153284D01*
X435011Y-153491D01*
Y-153901D01*
X435285Y-154563D01*
X435791Y-155069D01*
X436453Y-155343D01*
X437169D01*
X437831Y-155069D01*
X438337Y-154563D01*
X438611Y-153901D01*
Y-153185D01*
X438337Y-152524D01*
X437831Y-152017D01*
X437169Y-151743D01*
X436759D01*
X436552Y-151243D01*
X462661Y-125135D01*
X463161Y-125342D01*
Y-125555D01*
X463435Y-126216D01*
X463941Y-126723D01*
X464603Y-126997D01*
X465319D01*
X465980Y-126723D01*
X466487Y-126216D01*
X466761Y-125555D01*
Y-124839D01*
X466487Y-124177D01*
X465980Y-123671D01*
X465319Y-123397D01*
X465105D01*
X464898Y-122897D01*
X485617Y-102178D01*
X486861Y-101274D01*
X488086Y-100050D01*
X488990Y-98806D01*
X527953Y-59842D01*
Y-55118D01*
X527953D01*
Y-22441D01*
X605118D01*
Y-42913D01*
D02*
G37*
G36*
X40157Y-360236D02*
X7874D01*
Y-235828D01*
X8374Y-235728D01*
X8481Y-235987D01*
X8988Y-236494D01*
X9649Y-236768D01*
X10365D01*
X11027Y-236494D01*
X11533Y-235987D01*
X11807Y-235326D01*
Y-234610D01*
X11533Y-233948D01*
X11027Y-233442D01*
X10365Y-233168D01*
X9649D01*
X8988Y-233442D01*
X8481Y-233948D01*
X8374Y-234207D01*
X7874Y-234108D01*
Y-186986D01*
X8104Y-186876D01*
X8374Y-186832D01*
X8823Y-187281D01*
X9484Y-187555D01*
X10201D01*
X10862Y-187281D01*
X11368Y-186775D01*
X11643Y-186113D01*
Y-185397D01*
X11368Y-184736D01*
X10862Y-184229D01*
X10201Y-183955D01*
X9484D01*
X8823Y-184229D01*
X8374Y-184678D01*
X8104Y-184634D01*
X7874Y-184525D01*
Y-125591D01*
X11471D01*
X11476Y-125594D01*
X11763Y-126091D01*
X11586Y-126520D01*
Y-127236D01*
X11860Y-127897D01*
X12366Y-128404D01*
X13028Y-128678D01*
X13744D01*
X14405Y-128404D01*
X14912Y-127897D01*
X15186Y-127236D01*
Y-126520D01*
X15008Y-126091D01*
X15295Y-125594D01*
X15301Y-125591D01*
X40157D01*
Y-360236D01*
D02*
G37*
G36*
X262027Y-161024D02*
X233858D01*
Y-170079D01*
X210630D01*
Y-143701D01*
X248031D01*
Y-123622D01*
X262027D01*
Y-161024D01*
D02*
G37*
G36*
X578740Y-212221D02*
X578114Y-212480D01*
X577608Y-212986D01*
X577334Y-213648D01*
Y-214364D01*
X577608Y-215025D01*
X578114Y-215532D01*
X578740Y-215791D01*
Y-259401D01*
X578690Y-259435D01*
X577974D01*
X577312Y-259709D01*
X576806Y-260215D01*
X576532Y-260877D01*
Y-261593D01*
X576806Y-262255D01*
X577312Y-262761D01*
X577974Y-263035D01*
X578690D01*
X578740Y-263069D01*
Y-270420D01*
X578240Y-270486D01*
X578147Y-270136D01*
X577730Y-269415D01*
X577140Y-268825D01*
X576419Y-268409D01*
X575614Y-268193D01*
X574780D01*
X573975Y-268409D01*
X573253Y-268825D01*
X572664Y-269415D01*
X572247Y-270136D01*
X572031Y-270941D01*
Y-271775D01*
X572247Y-272580D01*
X572664Y-273302D01*
X573253Y-273891D01*
X573975Y-274308D01*
X574305Y-274396D01*
X574239Y-274896D01*
X551968D01*
Y-257382D01*
Y-244205D01*
X552191Y-243668D01*
Y-242952D01*
X551968Y-242416D01*
Y-225197D01*
X469745D01*
Y-192520D01*
X578740D01*
Y-212221D01*
D02*
G37*
G36*
X579858Y-287885D02*
X569096D01*
X568889Y-287385D01*
X569051Y-287223D01*
X569325Y-286561D01*
Y-285845D01*
X569051Y-285183D01*
X568545Y-284677D01*
X567883Y-284403D01*
X567167D01*
X566506Y-284677D01*
X565999Y-285183D01*
X565725Y-285845D01*
Y-286561D01*
X565999Y-287223D01*
X566416Y-287639D01*
X566477Y-288033D01*
X566456Y-288250D01*
X566279Y-288514D01*
X566201Y-288905D01*
Y-289819D01*
X527559D01*
Y-295696D01*
X527434Y-295821D01*
X527160Y-296483D01*
Y-297199D01*
X527434Y-297860D01*
X527559Y-297985D01*
Y-325922D01*
X565748D01*
Y-343203D01*
X541110D01*
X541011Y-342703D01*
X541571Y-342471D01*
X542077Y-341965D01*
X542351Y-341303D01*
Y-340587D01*
X542077Y-339925D01*
X541571Y-339419D01*
X540909Y-339145D01*
X540193D01*
X539532Y-339419D01*
X539025Y-339925D01*
X538751Y-340587D01*
Y-341303D01*
X539025Y-341965D01*
X539532Y-342471D01*
X540092Y-342703D01*
X539992Y-343203D01*
X537880D01*
X537781Y-343222D01*
X537681D01*
X537588Y-343261D01*
X537490Y-343281D01*
X537406Y-343336D01*
X537314Y-343375D01*
X537270Y-343418D01*
X534384D01*
X534340Y-343375D01*
X534247Y-343336D01*
X534164Y-343281D01*
X534065Y-343261D01*
X533972Y-343222D01*
X533872D01*
X533774Y-343203D01*
X507220D01*
Y-322028D01*
X507720Y-321821D01*
X508183Y-322283D01*
X509100Y-322663D01*
X510093D01*
X511011Y-322283D01*
X511713Y-321581D01*
X512093Y-320664D01*
Y-319671D01*
X511713Y-318753D01*
X511011Y-318051D01*
X510093Y-317671D01*
X509100D01*
X508183Y-318051D01*
X507720Y-318514D01*
X507220Y-318307D01*
Y-303729D01*
X507312Y-303508D01*
Y-302792D01*
X507220Y-302571D01*
Y-299930D01*
X507838D01*
X508500Y-299656D01*
X509006Y-299149D01*
X509280Y-298488D01*
Y-297772D01*
X509006Y-297110D01*
X508500Y-296604D01*
X507838Y-296330D01*
X507220D01*
Y-276688D01*
X507609Y-276299D01*
X520998D01*
X521028Y-276329D01*
X521689Y-276603D01*
X522405D01*
X523067Y-276329D01*
X523097Y-276299D01*
X579858D01*
Y-287885D01*
D02*
G37*
%LPC*%
G36*
X226736Y-30877D02*
X226020D01*
X225358Y-31151D01*
X224852Y-31657D01*
X224578Y-32319D01*
Y-33035D01*
X224852Y-33697D01*
X225358Y-34203D01*
X226020Y-34477D01*
X226736D01*
X227398Y-34203D01*
X227904Y-33697D01*
X228178Y-33035D01*
Y-32319D01*
X227904Y-31657D01*
X227398Y-31151D01*
X226736Y-30877D01*
D02*
G37*
G36*
X155785Y-32107D02*
X155069D01*
X154407Y-32381D01*
X153901Y-32887D01*
X153627Y-33549D01*
Y-34265D01*
X153901Y-34927D01*
X154407Y-35433D01*
X155069Y-35707D01*
X155785D01*
X156446Y-35433D01*
X156953Y-34927D01*
X157227Y-34265D01*
Y-33549D01*
X156953Y-32887D01*
X156446Y-32381D01*
X155785Y-32107D01*
D02*
G37*
G36*
X118468Y-34420D02*
X117752D01*
X117091Y-34694D01*
X116584Y-35201D01*
X116310Y-35862D01*
Y-36579D01*
X116584Y-37240D01*
X117091Y-37746D01*
X117752Y-38021D01*
X118468D01*
X119130Y-37746D01*
X119636Y-37240D01*
X119910Y-36579D01*
Y-35862D01*
X119636Y-35201D01*
X119130Y-34694D01*
X118468Y-34420D01*
D02*
G37*
G36*
X168862Y-35995D02*
X168146D01*
X167484Y-36269D01*
X166978Y-36776D01*
X166704Y-37437D01*
Y-38153D01*
X166978Y-38815D01*
X167484Y-39321D01*
X168146Y-39595D01*
X168862D01*
X169524Y-39321D01*
X170030Y-38815D01*
X170304Y-38153D01*
Y-37437D01*
X170030Y-36776D01*
X169524Y-36269D01*
X168862Y-35995D01*
D02*
G37*
G36*
X221224Y-37964D02*
X220508D01*
X219847Y-38238D01*
X219340Y-38744D01*
X219066Y-39406D01*
Y-40122D01*
X219340Y-40783D01*
X219847Y-41290D01*
X220508Y-41564D01*
X221224D01*
X221886Y-41290D01*
X222392Y-40783D01*
X222666Y-40122D01*
Y-39406D01*
X222392Y-38744D01*
X221886Y-38238D01*
X221224Y-37964D01*
D02*
G37*
G36*
X157445Y-39932D02*
X156729D01*
X156067Y-40206D01*
X155561Y-40713D01*
X155287Y-41374D01*
Y-42090D01*
X155561Y-42752D01*
X156067Y-43258D01*
X156729Y-43532D01*
X157445D01*
X158106Y-43258D01*
X158613Y-42752D01*
X158887Y-42090D01*
Y-41374D01*
X158613Y-40713D01*
X158106Y-40206D01*
X157445Y-39932D01*
D02*
G37*
G36*
X215712Y-40326D02*
X214996D01*
X214335Y-40600D01*
X213828Y-41106D01*
X213554Y-41768D01*
Y-42484D01*
X213828Y-43146D01*
X214335Y-43652D01*
X214996Y-43926D01*
X215712D01*
X216374Y-43652D01*
X216880Y-43146D01*
X217154Y-42484D01*
Y-41768D01*
X216880Y-41106D01*
X216374Y-40600D01*
X215712Y-40326D01*
D02*
G37*
G36*
X210594Y-42294D02*
X209878D01*
X209217Y-42568D01*
X208710Y-43075D01*
X208436Y-43736D01*
Y-44453D01*
X208710Y-45114D01*
X209217Y-45620D01*
X209878Y-45895D01*
X210594D01*
X211256Y-45620D01*
X211762Y-45114D01*
X212036Y-44453D01*
Y-43736D01*
X211762Y-43075D01*
X211256Y-42568D01*
X210594Y-42294D01*
D02*
G37*
G36*
X169256D02*
X168540D01*
X167878Y-42568D01*
X167372Y-43075D01*
X167098Y-43736D01*
Y-44453D01*
X167372Y-45114D01*
X167878Y-45620D01*
X168540Y-45895D01*
X169256D01*
X169917Y-45620D01*
X170424Y-45114D01*
X170539Y-44834D01*
X170698Y-44453D01*
Y-43736D01*
X170424Y-43075D01*
X169917Y-42568D01*
X169256Y-42294D01*
D02*
G37*
G36*
X118075Y-45493D02*
X117359D01*
X116697Y-45767D01*
X116191Y-46273D01*
X115917Y-46935D01*
Y-47651D01*
X116191Y-48313D01*
X116697Y-48819D01*
X117359Y-49093D01*
X118075D01*
X118736Y-48819D01*
X119243Y-48313D01*
X119517Y-47651D01*
Y-46935D01*
X119243Y-46273D01*
X118736Y-45767D01*
X118075Y-45493D01*
D02*
G37*
G36*
X169256Y-47806D02*
X168540D01*
X167878Y-48080D01*
X167372Y-48587D01*
X167098Y-49248D01*
Y-49964D01*
X167372Y-50626D01*
X167878Y-51132D01*
X168540Y-51406D01*
X169256D01*
X169917Y-51132D01*
X170424Y-50626D01*
X170698Y-49964D01*
Y-49248D01*
X170424Y-48587D01*
X169917Y-48080D01*
X169256Y-47806D01*
D02*
G37*
G36*
X153114D02*
X152398D01*
X151736Y-48080D01*
X151230Y-48587D01*
X150956Y-49248D01*
Y-49964D01*
X151230Y-50626D01*
X151736Y-51132D01*
X152398Y-51406D01*
X153114D01*
X153776Y-51132D01*
X154282Y-50626D01*
X154556Y-49964D01*
Y-49248D01*
X154282Y-48587D01*
X153776Y-48080D01*
X153114Y-47806D01*
D02*
G37*
G36*
X122012Y-50956D02*
X121295D01*
X120634Y-51230D01*
X120128Y-51736D01*
X119853Y-52398D01*
Y-53114D01*
X120128Y-53776D01*
X120634Y-54282D01*
X121295Y-54556D01*
X122012D01*
X122673Y-54282D01*
X123179Y-53776D01*
X123453Y-53114D01*
Y-52398D01*
X123179Y-51736D01*
X122673Y-51230D01*
X122012Y-50956D01*
D02*
G37*
G36*
X210988Y-51350D02*
X210272D01*
X209610Y-51624D01*
X209104Y-52130D01*
X208830Y-52792D01*
Y-53508D01*
X209104Y-54169D01*
X209610Y-54676D01*
X210272Y-54950D01*
X210988D01*
X211649Y-54676D01*
X212156Y-54169D01*
X212430Y-53508D01*
Y-52792D01*
X212156Y-52130D01*
X211649Y-51624D01*
X210988Y-51350D01*
D02*
G37*
G36*
X138794Y-51096D02*
X137801D01*
X136883Y-51476D01*
X136181Y-52178D01*
X135801Y-53096D01*
Y-54089D01*
X136181Y-55006D01*
X136883Y-55708D01*
X137801Y-56088D01*
X138794D01*
X139711Y-55708D01*
X140413Y-55006D01*
X140793Y-54089D01*
Y-53096D01*
X140413Y-52178D01*
X139711Y-51476D01*
X138794Y-51096D01*
D02*
G37*
G36*
X153114Y-55680D02*
X152398D01*
X151736Y-55954D01*
X151230Y-56461D01*
X150956Y-57122D01*
Y-57838D01*
X151230Y-58500D01*
X151736Y-59006D01*
X152398Y-59280D01*
X153114D01*
X153776Y-59006D01*
X154282Y-58500D01*
X154556Y-57838D01*
Y-57122D01*
X154282Y-56461D01*
X153776Y-55954D01*
X153114Y-55680D01*
D02*
G37*
G36*
X121815Y-55729D02*
X121099D01*
X120437Y-56003D01*
X119931Y-56510D01*
X119657Y-57171D01*
Y-57887D01*
X119931Y-58549D01*
X120437Y-59055D01*
X121099Y-59329D01*
X121815D01*
X122476Y-59055D01*
X122983Y-58549D01*
X123257Y-57887D01*
Y-57171D01*
X122983Y-56510D01*
X122476Y-56003D01*
X121815Y-55729D01*
D02*
G37*
G36*
X209899Y-56889D02*
X209183D01*
X208522Y-57163D01*
X208015Y-57670D01*
X207741Y-58331D01*
Y-59047D01*
X208015Y-59709D01*
X208522Y-60215D01*
X209183Y-60489D01*
X209899D01*
X210561Y-60215D01*
X211067Y-59709D01*
X211341Y-59047D01*
Y-58331D01*
X211067Y-57670D01*
X210561Y-57163D01*
X209899Y-56889D01*
D02*
G37*
G36*
X108232Y-58043D02*
X107516D01*
X106854Y-58317D01*
X106348Y-58823D01*
X106074Y-59484D01*
Y-60201D01*
X106348Y-60862D01*
X106854Y-61369D01*
X107270Y-61540D01*
Y-62082D01*
X106854Y-62254D01*
X106348Y-62760D01*
X106074Y-63421D01*
Y-64138D01*
X106348Y-64799D01*
X106854Y-65306D01*
X107516Y-65579D01*
X108232D01*
X108894Y-65306D01*
X109400Y-64799D01*
X109674Y-64138D01*
Y-63421D01*
X109400Y-62760D01*
X108894Y-62254D01*
X108478Y-62082D01*
Y-61540D01*
X108894Y-61369D01*
X109400Y-60862D01*
X109674Y-60201D01*
Y-59484D01*
X109400Y-58823D01*
X108894Y-58317D01*
X108232Y-58043D01*
D02*
G37*
G36*
X99964D02*
X99248D01*
X98587Y-58317D01*
X98080Y-58823D01*
X97806Y-59484D01*
Y-60201D01*
X98080Y-60862D01*
X98587Y-61369D01*
X99002Y-61540D01*
Y-62082D01*
X98587Y-62254D01*
X98080Y-62760D01*
X97806Y-63421D01*
Y-64138D01*
X98080Y-64799D01*
X98587Y-65306D01*
X99248Y-65579D01*
X99964D01*
X100626Y-65306D01*
X101132Y-64799D01*
X101406Y-64138D01*
Y-63421D01*
X101132Y-62760D01*
X100626Y-62254D01*
X100211Y-62082D01*
Y-61540D01*
X100626Y-61369D01*
X101132Y-60862D01*
X101406Y-60201D01*
Y-59484D01*
X101132Y-58823D01*
X100626Y-58317D01*
X99964Y-58043D01*
D02*
G37*
G36*
X168862Y-63554D02*
X168146D01*
X167484Y-63828D01*
X166978Y-64335D01*
X166704Y-64996D01*
Y-65712D01*
X166978Y-66374D01*
X167484Y-66880D01*
X168146Y-67154D01*
X168862D01*
X169524Y-66880D01*
X170030Y-66374D01*
X170304Y-65712D01*
Y-64996D01*
X170030Y-64335D01*
X169524Y-63828D01*
X168862Y-63554D01*
D02*
G37*
G36*
X153114D02*
X152398D01*
X151736Y-63828D01*
X151230Y-64335D01*
X150956Y-64996D01*
Y-65712D01*
X151230Y-66374D01*
X151736Y-66880D01*
X152398Y-67154D01*
X153114D01*
X153776Y-66880D01*
X154282Y-66374D01*
X154556Y-65712D01*
Y-64996D01*
X154282Y-64335D01*
X153776Y-63828D01*
X153114Y-63554D01*
D02*
G37*
G36*
X117681D02*
X116965D01*
X116303Y-63828D01*
X115797Y-64335D01*
X115523Y-64996D01*
Y-65712D01*
X115797Y-66374D01*
X116303Y-66880D01*
X116965Y-67154D01*
X117681D01*
X118342Y-66880D01*
X118849Y-66374D01*
X119123Y-65712D01*
Y-64996D01*
X118849Y-64335D01*
X118342Y-63828D01*
X117681Y-63554D01*
D02*
G37*
G36*
X138794Y-66844D02*
X137801D01*
X136883Y-67224D01*
X136181Y-67926D01*
X135801Y-68844D01*
Y-69837D01*
X136181Y-70754D01*
X136883Y-71456D01*
X137801Y-71836D01*
X138794D01*
X139711Y-71456D01*
X140413Y-70754D01*
X140793Y-69837D01*
Y-68844D01*
X140413Y-67926D01*
X139711Y-67224D01*
X138794Y-66844D01*
D02*
G37*
G36*
X157838Y-71428D02*
X157122D01*
X156461Y-71702D01*
X155954Y-72209D01*
X155680Y-72870D01*
Y-73586D01*
X155954Y-74248D01*
X156461Y-74754D01*
X157122Y-75028D01*
X157838D01*
X158500Y-74754D01*
X159006Y-74248D01*
X159280Y-73586D01*
Y-72870D01*
X159006Y-72209D01*
X158500Y-71702D01*
X157838Y-71428D01*
D02*
G37*
G36*
X168862Y-69460D02*
X168146D01*
X167484Y-69734D01*
X166978Y-70240D01*
X166704Y-70902D01*
Y-71618D01*
X166978Y-72280D01*
X167139Y-72441D01*
X166978Y-72602D01*
X166704Y-73264D01*
Y-73980D01*
X166978Y-74642D01*
X167484Y-75148D01*
X168146Y-75422D01*
X168862D01*
X169524Y-75148D01*
X170030Y-74642D01*
X170304Y-73980D01*
Y-73264D01*
X170030Y-72602D01*
X169868Y-72441D01*
X170030Y-72280D01*
X170304Y-71618D01*
Y-70902D01*
X170030Y-70240D01*
X169524Y-69734D01*
X168862Y-69460D01*
D02*
G37*
G36*
X135791Y-77334D02*
X135075D01*
X134413Y-77608D01*
X133907Y-78114D01*
X133633Y-78776D01*
Y-79492D01*
X133907Y-80154D01*
X134413Y-80660D01*
X135075Y-80934D01*
X135791D01*
X136453Y-80660D01*
X136959Y-80154D01*
X137233Y-79492D01*
Y-78776D01*
X136959Y-78114D01*
X136453Y-77608D01*
X135791Y-77334D01*
D02*
G37*
G36*
X168862Y-77728D02*
X168146D01*
X167484Y-78002D01*
X166978Y-78508D01*
X166704Y-79169D01*
Y-79886D01*
X166978Y-80547D01*
X167484Y-81054D01*
X168146Y-81328D01*
X168862D01*
X169524Y-81054D01*
X170030Y-80547D01*
X170304Y-79886D01*
Y-79169D01*
X170030Y-78508D01*
X169524Y-78002D01*
X168862Y-77728D01*
D02*
G37*
G36*
X161775Y-93476D02*
X161059D01*
X160398Y-93750D01*
X159891Y-94256D01*
X159617Y-94918D01*
Y-95634D01*
X159891Y-96295D01*
X160398Y-96802D01*
X161059Y-97076D01*
X161775D01*
X162437Y-96802D01*
X162943Y-96295D01*
X163217Y-95634D01*
Y-94918D01*
X162943Y-94256D01*
X162437Y-93750D01*
X161775Y-93476D01*
D02*
G37*
G36*
X38941Y-56555D02*
X38225D01*
X37563Y-56829D01*
X37057Y-57336D01*
X36783Y-57997D01*
Y-58713D01*
X37057Y-59375D01*
X37563Y-59881D01*
X38225Y-60155D01*
X38941D01*
X39602Y-59881D01*
X40109Y-59375D01*
X40383Y-58713D01*
Y-57997D01*
X40109Y-57336D01*
X39602Y-56829D01*
X38941Y-56555D01*
D02*
G37*
G36*
X383823Y-101743D02*
X383106D01*
X382445Y-102017D01*
X381939Y-102524D01*
X381665Y-103185D01*
Y-103901D01*
X381939Y-104563D01*
X382445Y-105069D01*
X383106Y-105343D01*
X383823D01*
X384484Y-105069D01*
X384991Y-104563D01*
X385265Y-103901D01*
Y-103185D01*
X384991Y-102524D01*
X384484Y-102017D01*
X383823Y-101743D01*
D02*
G37*
G36*
X366446Y-83557D02*
X364715D01*
X363005Y-83828D01*
X361358Y-84363D01*
X359816Y-85149D01*
X358415Y-86166D01*
X357190Y-87391D01*
X356173Y-88792D01*
X355387Y-90334D01*
X354852Y-91981D01*
X354581Y-93691D01*
Y-95423D01*
X354852Y-97133D01*
X355387Y-98779D01*
X356173Y-100322D01*
X357190Y-101723D01*
X358415Y-102947D01*
X359816Y-103965D01*
X361358Y-104751D01*
X363005Y-105286D01*
X364715Y-105557D01*
X366446D01*
X368157Y-105286D01*
X369803Y-104751D01*
X371346Y-103965D01*
X372747Y-102947D01*
X373971Y-101723D01*
X374989Y-100322D01*
X375775Y-98779D01*
X376310Y-97133D01*
X376581Y-95423D01*
Y-93691D01*
X376310Y-91981D01*
X375775Y-90334D01*
X374989Y-88792D01*
X373971Y-87391D01*
X372747Y-86166D01*
X371346Y-85149D01*
X369803Y-84363D01*
X368157Y-83828D01*
X366446Y-83557D01*
D02*
G37*
G36*
X391012Y-102710D02*
X390296D01*
X389634Y-102984D01*
X389128Y-103490D01*
X388854Y-104152D01*
Y-104868D01*
X389128Y-105529D01*
X389634Y-106036D01*
X390296Y-106310D01*
X391012D01*
X391673Y-106036D01*
X392180Y-105529D01*
X392454Y-104868D01*
Y-104152D01*
X392180Y-103490D01*
X391673Y-102984D01*
X391012Y-102710D01*
D02*
G37*
G36*
X355393Y-104076D02*
X354677D01*
X354015Y-104350D01*
X353509Y-104856D01*
X353235Y-105518D01*
Y-106234D01*
X353509Y-106895D01*
X354015Y-107402D01*
X354677Y-107676D01*
X355393D01*
X356054Y-107402D01*
X356561Y-106895D01*
X356835Y-106234D01*
Y-105518D01*
X356561Y-104856D01*
X356054Y-104350D01*
X355393Y-104076D01*
D02*
G37*
G36*
X238547Y-105287D02*
X237831D01*
X237169Y-105561D01*
X236663Y-106067D01*
X236389Y-106729D01*
Y-107445D01*
X236663Y-108106D01*
X237169Y-108613D01*
X237831Y-108887D01*
X238547D01*
X239209Y-108613D01*
X239715Y-108106D01*
X239989Y-107445D01*
Y-106729D01*
X239715Y-106067D01*
X239209Y-105561D01*
X238547Y-105287D01*
D02*
G37*
G36*
X233429D02*
X232713D01*
X232051Y-105561D01*
X231545Y-106067D01*
X231271Y-106729D01*
Y-107445D01*
X231545Y-108106D01*
X232051Y-108613D01*
X232713Y-108887D01*
X233429D01*
X234090Y-108613D01*
X234597Y-108106D01*
X234871Y-107445D01*
Y-106729D01*
X234597Y-106067D01*
X234090Y-105561D01*
X233429Y-105287D01*
D02*
G37*
G36*
X228705Y-105680D02*
X227988D01*
X227327Y-105954D01*
X226820Y-106461D01*
X226547Y-107122D01*
Y-107838D01*
X226820Y-108500D01*
X227327Y-109006D01*
X227988Y-109280D01*
X228705D01*
X229366Y-109006D01*
X229872Y-108500D01*
X230147Y-107838D01*
Y-107122D01*
X229872Y-106461D01*
X229366Y-105954D01*
X228705Y-105680D01*
D02*
G37*
G36*
X223586D02*
X222870D01*
X222209Y-105954D01*
X221702Y-106461D01*
X221428Y-107122D01*
Y-107838D01*
X221702Y-108500D01*
X222209Y-109006D01*
X222870Y-109280D01*
X223586D01*
X224248Y-109006D01*
X224754Y-108500D01*
X225028Y-107838D01*
Y-107122D01*
X224754Y-106461D01*
X224248Y-105954D01*
X223586Y-105680D01*
D02*
G37*
G36*
X263082Y-106013D02*
X262366D01*
X261704Y-106287D01*
X261198Y-106793D01*
X260924Y-107455D01*
Y-108171D01*
X261198Y-108832D01*
X261704Y-109339D01*
X262366Y-109613D01*
X263082D01*
X263743Y-109339D01*
X264250Y-108832D01*
X264524Y-108171D01*
Y-107455D01*
X264250Y-106793D01*
X263743Y-106287D01*
X263082Y-106013D01*
D02*
G37*
G36*
X58568Y-106261D02*
X57852D01*
X57190Y-106535D01*
X56684Y-107041D01*
X56410Y-107703D01*
Y-108419D01*
X56684Y-109081D01*
X57190Y-109587D01*
X57852Y-109861D01*
X58568D01*
X59229Y-109587D01*
X59736Y-109081D01*
X60010Y-108419D01*
Y-107703D01*
X59736Y-107041D01*
X59229Y-106535D01*
X58568Y-106261D01*
D02*
G37*
G36*
X253440Y-108436D02*
X252724D01*
X252062Y-108710D01*
X251556Y-109217D01*
X251282Y-109878D01*
Y-110594D01*
X251556Y-111256D01*
X252062Y-111762D01*
X252724Y-112036D01*
X253440D01*
X254101Y-111762D01*
X254608Y-111256D01*
X254882Y-110594D01*
Y-109878D01*
X254608Y-109217D01*
X254101Y-108710D01*
X253440Y-108436D01*
D02*
G37*
G36*
X124374D02*
X123658D01*
X122996Y-108710D01*
X122490Y-109217D01*
X122216Y-109878D01*
Y-110594D01*
X122490Y-111256D01*
X122996Y-111762D01*
X123658Y-112036D01*
X124374D01*
X125035Y-111762D01*
X125542Y-111256D01*
X125816Y-110594D01*
Y-109878D01*
X125542Y-109217D01*
X125035Y-108710D01*
X124374Y-108436D01*
D02*
G37*
G36*
X168701Y-109027D02*
X167985D01*
X167323Y-109301D01*
X166817Y-109807D01*
X166543Y-110469D01*
Y-111185D01*
X166817Y-111846D01*
X167323Y-112353D01*
X167985Y-112627D01*
X168701D01*
X169363Y-112353D01*
X169869Y-111846D01*
X170143Y-111185D01*
Y-110469D01*
X169869Y-109807D01*
X169363Y-109301D01*
X168701Y-109027D01*
D02*
G37*
G36*
X192484Y-110011D02*
X191768D01*
X191106Y-110285D01*
X190600Y-110791D01*
X190326Y-111453D01*
Y-112169D01*
X190600Y-112831D01*
X191106Y-113337D01*
X191768Y-113611D01*
X192484D01*
X193146Y-113337D01*
X193652Y-112831D01*
X193926Y-112169D01*
Y-111453D01*
X193652Y-110791D01*
X193146Y-110285D01*
X192484Y-110011D01*
D02*
G37*
G36*
X157284Y-109814D02*
X156568D01*
X155906Y-110088D01*
X155400Y-110595D01*
X155126Y-111256D01*
Y-111972D01*
X155400Y-112634D01*
X155906Y-113140D01*
X156568Y-113414D01*
X157284D01*
X157899Y-113159D01*
X158067Y-113132D01*
X158462Y-113211D01*
X158549Y-113421D01*
X159056Y-113927D01*
X159717Y-114202D01*
X160433D01*
X161095Y-113927D01*
X161601Y-113421D01*
X161875Y-112760D01*
Y-112043D01*
X161601Y-111382D01*
X161095Y-110876D01*
X160433Y-110602D01*
X159717D01*
X159101Y-110857D01*
X158934Y-110883D01*
X158539Y-110805D01*
X158452Y-110595D01*
X157945Y-110088D01*
X157284Y-109814D01*
D02*
G37*
G36*
X347602Y-111389D02*
X346886D01*
X346224Y-111663D01*
X345718Y-112169D01*
X345444Y-112831D01*
Y-113547D01*
X345718Y-114209D01*
X346224Y-114715D01*
X346886Y-114989D01*
X347602D01*
X348264Y-114715D01*
X348770Y-114209D01*
X349044Y-113547D01*
Y-112831D01*
X348770Y-112169D01*
X348264Y-111663D01*
X347602Y-111389D01*
D02*
G37*
G36*
X153508Y-111586D02*
X152792D01*
X152130Y-111860D01*
X151624Y-112366D01*
X151350Y-113028D01*
Y-113744D01*
X151624Y-114405D01*
X152130Y-114912D01*
X152792Y-115186D01*
X153508D01*
X154169Y-114912D01*
X154676Y-114405D01*
X154950Y-113744D01*
Y-113028D01*
X154676Y-112366D01*
X154169Y-111860D01*
X153508Y-111586D01*
D02*
G37*
G36*
X165201Y-112240D02*
X164485D01*
X163823Y-112514D01*
X163317Y-113020D01*
X163043Y-113681D01*
Y-114398D01*
X163317Y-115059D01*
X163823Y-115566D01*
X164485Y-115840D01*
X165201D01*
X165862Y-115566D01*
X166369Y-115059D01*
X166643Y-114398D01*
Y-113681D01*
X166369Y-113020D01*
X165862Y-112514D01*
X165201Y-112240D01*
D02*
G37*
G36*
X44492Y-113280D02*
X43776D01*
X43114Y-113554D01*
X42608Y-114060D01*
X42334Y-114722D01*
Y-115438D01*
X42608Y-116100D01*
X43114Y-116606D01*
X43776Y-116880D01*
X44492D01*
X45153Y-116606D01*
X45660Y-116100D01*
X45934Y-115438D01*
Y-114722D01*
X45660Y-114060D01*
X45153Y-113554D01*
X44492Y-113280D01*
D02*
G37*
G36*
X245634Y-113948D02*
X244917D01*
X244256Y-114222D01*
X243750Y-114728D01*
X243476Y-115390D01*
Y-116106D01*
X243750Y-116768D01*
X244256Y-117274D01*
X244917Y-117548D01*
X245634D01*
X246295Y-117274D01*
X246801Y-116768D01*
X247076Y-116106D01*
Y-115390D01*
X246801Y-114728D01*
X246295Y-114222D01*
X245634Y-113948D01*
D02*
G37*
G36*
X173586Y-115523D02*
X172870D01*
X172209Y-115797D01*
X171702Y-116303D01*
X171428Y-116965D01*
Y-117681D01*
X171702Y-118342D01*
X172209Y-118849D01*
X172870Y-119123D01*
X173586D01*
X174248Y-118849D01*
X174754Y-118342D01*
X175028Y-117681D01*
Y-116965D01*
X174754Y-116303D01*
X174248Y-115797D01*
X173586Y-115523D01*
D02*
G37*
G36*
X188386Y-111783D02*
X187670D01*
X187008Y-112057D01*
X186502Y-112563D01*
X186228Y-113225D01*
Y-113941D01*
X186502Y-114602D01*
X187008Y-115109D01*
X187670Y-115383D01*
X188263D01*
X188363Y-115883D01*
X188189Y-115954D01*
X187683Y-116461D01*
X187409Y-117122D01*
Y-117838D01*
X187683Y-118500D01*
X188189Y-119006D01*
X188851Y-119280D01*
X189567D01*
X190229Y-119006D01*
X190735Y-118500D01*
X191009Y-117838D01*
Y-117122D01*
X190735Y-116461D01*
X190229Y-115954D01*
X189567Y-115680D01*
X188974D01*
X188875Y-115180D01*
X189048Y-115109D01*
X189554Y-114602D01*
X189828Y-113941D01*
Y-113225D01*
X189554Y-112563D01*
X189048Y-112057D01*
X188386Y-111783D01*
D02*
G37*
G36*
X298565Y-111461D02*
X297498D01*
X296468Y-111737D01*
X295544Y-112270D01*
X294790Y-113024D01*
X294256Y-113948D01*
X293980Y-114979D01*
Y-116045D01*
X294256Y-117076D01*
X294790Y-117999D01*
X295544Y-118754D01*
X296468Y-119287D01*
X297498Y-119563D01*
X298565D01*
X299595Y-119287D01*
X300519Y-118754D01*
X301273Y-117999D01*
X301807Y-117076D01*
X302083Y-116045D01*
Y-114979D01*
X301807Y-113948D01*
X301273Y-113024D01*
X300519Y-112270D01*
X299595Y-111737D01*
X298565Y-111461D01*
D02*
G37*
G36*
X89670Y-117678D02*
X88954D01*
X88292Y-117952D01*
X87786Y-118459D01*
X87512Y-119120D01*
Y-119836D01*
X87786Y-120498D01*
X88292Y-121004D01*
X88954Y-121278D01*
X89670D01*
X90332Y-121004D01*
X90838Y-120498D01*
X91112Y-119836D01*
Y-119120D01*
X90838Y-118459D01*
X90332Y-117952D01*
X89670Y-117678D01*
D02*
G37*
G36*
X85339D02*
X84623D01*
X83962Y-117952D01*
X83455Y-118459D01*
X83181Y-119120D01*
Y-119836D01*
X83455Y-120498D01*
X83962Y-121004D01*
X84623Y-121278D01*
X85339D01*
X86001Y-121004D01*
X86507Y-120498D01*
X86781Y-119836D01*
Y-119120D01*
X86507Y-118459D01*
X86001Y-117952D01*
X85339Y-117678D01*
D02*
G37*
G36*
X81009D02*
X80293D01*
X79631Y-117952D01*
X79125Y-118459D01*
X78851Y-119120D01*
Y-119836D01*
X79125Y-120498D01*
X79631Y-121004D01*
X80293Y-121278D01*
X81009D01*
X81670Y-121004D01*
X82177Y-120498D01*
X82451Y-119836D01*
Y-119120D01*
X82177Y-118459D01*
X81670Y-117952D01*
X81009Y-117678D01*
D02*
G37*
G36*
X347996Y-118082D02*
X347280D01*
X346618Y-118356D01*
X346112Y-118862D01*
X345838Y-119524D01*
Y-120240D01*
X346112Y-120902D01*
X346618Y-121408D01*
X347280Y-121682D01*
X347996D01*
X348657Y-121408D01*
X349164Y-120902D01*
X349438Y-120240D01*
Y-119524D01*
X349164Y-118862D01*
X348657Y-118356D01*
X347996Y-118082D01*
D02*
G37*
G36*
X133457Y-118184D02*
X132741D01*
X132079Y-118458D01*
X131573Y-118964D01*
X131299Y-119626D01*
Y-120342D01*
X131573Y-121003D01*
X132079Y-121510D01*
X132741Y-121784D01*
X133457D01*
X134118Y-121510D01*
X134625Y-121003D01*
X134899Y-120342D01*
Y-119626D01*
X134625Y-118964D01*
X134118Y-118458D01*
X133457Y-118184D01*
D02*
G37*
G36*
X152756Y-115917D02*
X152040D01*
X151379Y-116191D01*
X150872Y-116697D01*
X150598Y-117359D01*
Y-117620D01*
X150591Y-118075D01*
X150136Y-118082D01*
X149875D01*
X149213Y-118356D01*
X148707Y-118862D01*
X148433Y-119524D01*
Y-120240D01*
X148707Y-120902D01*
X149213Y-121408D01*
X149875Y-121682D01*
X150591D01*
X150925Y-121543D01*
X151425Y-121877D01*
Y-122105D01*
X151699Y-122766D01*
X151311Y-123037D01*
X150954Y-122680D01*
X150293Y-122406D01*
X149577D01*
X148915Y-122680D01*
X148409Y-123186D01*
X148135Y-123847D01*
Y-124564D01*
X148409Y-125225D01*
X148915Y-125732D01*
X148982Y-126067D01*
X148707Y-126343D01*
X148433Y-127004D01*
Y-127720D01*
X148707Y-128382D01*
X149213Y-128888D01*
X149295Y-129298D01*
X149100Y-129492D01*
X148827Y-130154D01*
Y-130870D01*
X149100Y-131531D01*
X149607Y-132038D01*
X150268Y-132312D01*
X150985D01*
X151646Y-132038D01*
X152152Y-131531D01*
X152427Y-130870D01*
Y-130154D01*
X152152Y-129492D01*
X151646Y-128986D01*
X151565Y-128576D01*
X151759Y-128382D01*
X152033Y-127720D01*
Y-127004D01*
X151759Y-126343D01*
X151601Y-126185D01*
X151693Y-125569D01*
X151707Y-125561D01*
X151885Y-125739D01*
X152546Y-126013D01*
X153262D01*
X153924Y-125739D01*
X154430Y-125232D01*
X154704Y-124571D01*
Y-123855D01*
X154430Y-123193D01*
X154377Y-123140D01*
X154751Y-122766D01*
X155025Y-122105D01*
Y-121389D01*
X154751Y-120727D01*
X154245Y-120221D01*
X153584Y-119947D01*
X153184D01*
X153024Y-119947D01*
X152925Y-119447D01*
X153068Y-119387D01*
X153418Y-119243D01*
X153924Y-118736D01*
X154198Y-118075D01*
Y-117359D01*
X153924Y-116697D01*
X153418Y-116191D01*
X152756Y-115917D01*
D02*
G37*
G36*
X89670Y-122009D02*
X88954D01*
X88292Y-122283D01*
X87786Y-122790D01*
X87512Y-123451D01*
Y-124167D01*
X87786Y-124829D01*
X88292Y-125335D01*
X88954Y-125609D01*
X89670D01*
X90332Y-125335D01*
X90838Y-124829D01*
X91112Y-124167D01*
Y-123451D01*
X90838Y-122790D01*
X90332Y-122283D01*
X89670Y-122009D01*
D02*
G37*
G36*
X85339D02*
X84623D01*
X83962Y-122283D01*
X83455Y-122790D01*
X83181Y-123451D01*
Y-124167D01*
X83455Y-124829D01*
X83962Y-125335D01*
X84623Y-125609D01*
X85339D01*
X86001Y-125335D01*
X86507Y-124829D01*
X86781Y-124167D01*
Y-123451D01*
X86507Y-122790D01*
X86001Y-122283D01*
X85339Y-122009D01*
D02*
G37*
G36*
X81009D02*
X80293D01*
X79631Y-122283D01*
X79125Y-122790D01*
X78851Y-123451D01*
Y-124167D01*
X79125Y-124829D01*
X79631Y-125335D01*
X80293Y-125609D01*
X81009D01*
X81670Y-125335D01*
X82177Y-124829D01*
X82451Y-124167D01*
Y-123451D01*
X82177Y-122790D01*
X81670Y-122283D01*
X81009Y-122009D01*
D02*
G37*
G36*
X281854Y-122609D02*
X281138D01*
X280476Y-122883D01*
X279970Y-123390D01*
X279696Y-124051D01*
Y-124767D01*
X279970Y-125429D01*
X280476Y-125935D01*
X281138Y-126209D01*
X281854D01*
X282516Y-125935D01*
X283022Y-125429D01*
X283296Y-124767D01*
Y-124051D01*
X283022Y-123390D01*
X282516Y-122883D01*
X281854Y-122609D01*
D02*
G37*
G36*
X173819Y-125562D02*
X173103D01*
X172441Y-125836D01*
X171935Y-126343D01*
X171661Y-127004D01*
Y-127720D01*
X171935Y-128382D01*
X172441Y-128888D01*
X173103Y-129162D01*
X173819D01*
X174481Y-128888D01*
X174987Y-128382D01*
X175261Y-127720D01*
Y-127004D01*
X174987Y-126343D01*
X174481Y-125836D01*
X173819Y-125562D01*
D02*
G37*
G36*
X298565Y-121461D02*
X297498D01*
X296468Y-121737D01*
X295544Y-122270D01*
X294790Y-123024D01*
X294256Y-123948D01*
X293980Y-124978D01*
Y-126045D01*
X294256Y-127076D01*
X294790Y-127999D01*
X295544Y-128754D01*
X296468Y-129287D01*
X297498Y-129563D01*
X298565D01*
X299595Y-129287D01*
X300519Y-128754D01*
X301273Y-127999D01*
X301807Y-127076D01*
X302083Y-126045D01*
Y-124978D01*
X301807Y-123948D01*
X301273Y-123024D01*
X300519Y-122270D01*
X299595Y-121737D01*
X298565Y-121461D01*
D02*
G37*
G36*
X89670Y-126340D02*
X88954D01*
X88292Y-126614D01*
X87786Y-127120D01*
X87512Y-127782D01*
Y-128498D01*
X87786Y-129159D01*
X88292Y-129666D01*
X88954Y-129940D01*
X89670D01*
X90332Y-129666D01*
X90838Y-129159D01*
X91112Y-128498D01*
Y-127782D01*
X90838Y-127120D01*
X90332Y-126614D01*
X89670Y-126340D01*
D02*
G37*
G36*
X85339D02*
X84623D01*
X83962Y-126614D01*
X83455Y-127120D01*
X83181Y-127782D01*
Y-128498D01*
X83455Y-129159D01*
X83962Y-129666D01*
X84623Y-129940D01*
X85339D01*
X86001Y-129666D01*
X86507Y-129159D01*
X86781Y-128498D01*
Y-127782D01*
X86507Y-127120D01*
X86001Y-126614D01*
X85339Y-126340D01*
D02*
G37*
G36*
X81009D02*
X80293D01*
X79631Y-126614D01*
X79125Y-127120D01*
X78851Y-127782D01*
Y-128498D01*
X79125Y-129159D01*
X79631Y-129666D01*
X80293Y-129940D01*
X81009D01*
X81670Y-129666D01*
X82177Y-129159D01*
X82451Y-128498D01*
Y-127782D01*
X82177Y-127120D01*
X81670Y-126614D01*
X81009Y-126340D01*
D02*
G37*
G36*
X286578Y-123003D02*
X285862D01*
X285201Y-123277D01*
X284695Y-123784D01*
X284420Y-124445D01*
Y-125161D01*
X284695Y-125823D01*
X284918Y-126047D01*
X284711Y-126547D01*
X284288D01*
X283626Y-126821D01*
X283120Y-127327D01*
X282846Y-127988D01*
Y-128705D01*
X283120Y-129366D01*
X283626Y-129872D01*
X284288Y-130147D01*
X285004D01*
X285665Y-129872D01*
X286172Y-129366D01*
X286446Y-128705D01*
Y-127988D01*
X286172Y-127327D01*
X285948Y-127103D01*
X286155Y-126603D01*
X286578D01*
X287240Y-126329D01*
X287746Y-125823D01*
X288020Y-125161D01*
Y-124445D01*
X287746Y-123784D01*
X287240Y-123277D01*
X286818Y-123102D01*
D01*
X286578Y-123003D01*
D02*
G37*
G36*
X277008Y-127010D02*
X276292D01*
X275630Y-127284D01*
X275124Y-127791D01*
X274850Y-128452D01*
Y-129168D01*
X275124Y-129830D01*
X275630Y-130336D01*
X276292Y-130610D01*
X277008D01*
X277670Y-130336D01*
X278176Y-129830D01*
X278450Y-129168D01*
Y-128452D01*
X278176Y-127791D01*
X277670Y-127284D01*
X277008Y-127010D01*
D02*
G37*
G36*
X57780Y-127127D02*
X57064D01*
X56403Y-127401D01*
X55896Y-127908D01*
X55622Y-128569D01*
Y-129285D01*
X55896Y-129947D01*
X56403Y-130453D01*
X57064Y-130727D01*
X57780D01*
X58442Y-130453D01*
X58948Y-129947D01*
X59222Y-129285D01*
Y-128569D01*
X58948Y-127908D01*
X58442Y-127401D01*
X57780Y-127127D01*
D02*
G37*
G36*
X99119Y-115946D02*
X98403D01*
X97741Y-116220D01*
X97235Y-116727D01*
X96961Y-117388D01*
Y-118104D01*
X97235Y-118766D01*
X97741Y-119272D01*
X98403Y-119546D01*
X98929D01*
Y-120071D01*
X98403D01*
X97741Y-120345D01*
X97235Y-120852D01*
X96961Y-121513D01*
Y-122230D01*
X97235Y-122891D01*
X97741Y-123397D01*
X98253Y-123609D01*
Y-124133D01*
X97741Y-124346D01*
X97235Y-124852D01*
X96961Y-125513D01*
Y-126230D01*
X97235Y-126891D01*
X97741Y-127397D01*
X98255Y-127610D01*
Y-128133D01*
X97741Y-128346D01*
X97235Y-128852D01*
X96961Y-129514D01*
Y-130230D01*
X97235Y-130892D01*
X97741Y-131398D01*
X98403Y-131672D01*
X99119D01*
X99780Y-131398D01*
X100287Y-130892D01*
X100561Y-130230D01*
Y-129672D01*
X101087D01*
X101749Y-129397D01*
X102255Y-128891D01*
X102529Y-128229D01*
Y-127513D01*
X102255Y-126852D01*
X101749Y-126346D01*
X101237Y-126133D01*
Y-125610D01*
X101749Y-125397D01*
X102255Y-124891D01*
X102529Y-124230D01*
Y-123513D01*
X102255Y-122852D01*
X101749Y-122345D01*
X101237Y-122133D01*
Y-121609D01*
X101749Y-121397D01*
X102255Y-120891D01*
X102529Y-120229D01*
Y-119513D01*
X102255Y-118852D01*
X101749Y-118345D01*
X101087Y-118071D01*
X100561D01*
Y-117388D01*
X100287Y-116727D01*
X99780Y-116220D01*
X99119Y-115946D01*
D02*
G37*
G36*
X140428Y-130585D02*
X139712D01*
X139050Y-130859D01*
X138544Y-131366D01*
X138270Y-132027D01*
Y-132743D01*
X138544Y-133405D01*
X139050Y-133911D01*
X139712Y-134185D01*
X140428D01*
X141089Y-133911D01*
X141596Y-133405D01*
X141870Y-132743D01*
Y-132027D01*
X141596Y-131366D01*
X141089Y-130859D01*
X140428Y-130585D01*
D02*
G37*
G36*
X298565Y-131461D02*
X297498D01*
X296468Y-131737D01*
X295544Y-132270D01*
X294790Y-133024D01*
X294256Y-133948D01*
X293980Y-134978D01*
Y-136045D01*
X294256Y-137075D01*
X294790Y-137999D01*
X295544Y-138754D01*
X296468Y-139287D01*
X297498Y-139563D01*
X298565D01*
X299595Y-139287D01*
X300519Y-138754D01*
X301273Y-137999D01*
X301807Y-137075D01*
X302083Y-136045D01*
Y-134978D01*
X301807Y-133948D01*
X301273Y-133024D01*
X300519Y-132270D01*
X299595Y-131737D01*
X298565Y-131461D01*
D02*
G37*
G36*
X286185Y-135995D02*
X285469D01*
X284807Y-136269D01*
X284301Y-136776D01*
X284027Y-137437D01*
Y-138153D01*
X284301Y-138815D01*
X284807Y-139321D01*
X285469Y-139595D01*
X286185D01*
X286846Y-139321D01*
X287353Y-138815D01*
X287627Y-138153D01*
Y-137437D01*
X287353Y-136776D01*
X286846Y-136269D01*
X286185Y-135995D01*
D02*
G37*
G36*
X281067D02*
X280351D01*
X279689Y-136269D01*
X279183Y-136776D01*
X278909Y-137437D01*
Y-138153D01*
X279183Y-138815D01*
X279689Y-139321D01*
X280351Y-139595D01*
X281067D01*
X281728Y-139321D01*
X282235Y-138815D01*
X282509Y-138153D01*
Y-137437D01*
X282235Y-136776D01*
X281728Y-136269D01*
X281067Y-135995D01*
D02*
G37*
G36*
X276441Y-139342D02*
X275725D01*
X275063Y-139616D01*
X274557Y-140122D01*
X274283Y-140784D01*
Y-141500D01*
X274557Y-142161D01*
X275063Y-142668D01*
X275725Y-142942D01*
X276441D01*
X277102Y-142668D01*
X277609Y-142161D01*
X277883Y-141500D01*
Y-140784D01*
X277609Y-140122D01*
X277102Y-139616D01*
X276441Y-139342D01*
D02*
G37*
G36*
X284610Y-142295D02*
X283894D01*
X283232Y-142569D01*
X282726Y-143075D01*
X282452Y-143736D01*
Y-144453D01*
X282726Y-145114D01*
X283232Y-145621D01*
X283894Y-145895D01*
X284610D01*
X285272Y-145621D01*
X285778Y-145114D01*
X286052Y-144453D01*
Y-143736D01*
X285778Y-143075D01*
X285272Y-142569D01*
X284610Y-142295D01*
D02*
G37*
G36*
X298565Y-141461D02*
X297498D01*
X296468Y-141737D01*
X295544Y-142270D01*
X294790Y-143024D01*
X294256Y-143948D01*
X293980Y-144978D01*
Y-146045D01*
X294256Y-147075D01*
X294790Y-147999D01*
X295544Y-148754D01*
X296468Y-149287D01*
X297498Y-149563D01*
X298565D01*
X299595Y-149287D01*
X300519Y-148754D01*
X301273Y-147999D01*
X301807Y-147075D01*
X302083Y-146045D01*
Y-144978D01*
X301807Y-143948D01*
X301273Y-143024D01*
X300519Y-142270D01*
X299595Y-141737D01*
X298565Y-141461D01*
D02*
G37*
G36*
X111382Y17154D02*
X110666D01*
X110004Y16880D01*
X109498Y16374D01*
X109224Y15712D01*
Y14996D01*
X109498Y14335D01*
X110004Y13828D01*
X110666Y13554D01*
X111382D01*
X112043Y13828D01*
X112550Y14335D01*
X112824Y14996D01*
Y15712D01*
X112550Y16374D01*
X112043Y16880D01*
X111382Y17154D01*
D02*
G37*
G36*
X107051D02*
X106335D01*
X105673Y16880D01*
X105167Y16374D01*
X104893Y15712D01*
Y14996D01*
X105167Y14335D01*
X105673Y13828D01*
X106335Y13554D01*
X107051D01*
X107712Y13828D01*
X108219Y14335D01*
X108493Y14996D01*
Y15712D01*
X108219Y16374D01*
X107712Y16880D01*
X107051Y17154D01*
D02*
G37*
G36*
X111382Y11249D02*
X110666D01*
X110004Y10975D01*
X109498Y10468D01*
X109326Y10053D01*
X108784D01*
X108613Y10468D01*
X108106Y10975D01*
X107445Y11249D01*
X106729D01*
X106067Y10975D01*
X105561Y10468D01*
X105287Y9807D01*
Y9091D01*
X105561Y8429D01*
X106067Y7923D01*
X106729Y7649D01*
X107445D01*
X108106Y7923D01*
X108613Y8429D01*
X108784Y8844D01*
X109326D01*
X109498Y8429D01*
X110004Y7923D01*
X110666Y7649D01*
X111382D01*
X112043Y7923D01*
X112550Y8429D01*
X112824Y9091D01*
Y9807D01*
X112550Y10468D01*
X112043Y10975D01*
X111382Y11249D01*
D02*
G37*
G36*
X57051Y2860D02*
X56335D01*
X55673Y2585D01*
X55167Y2079D01*
X54893Y1418D01*
Y702D01*
X55167Y40D01*
X55673Y-466D01*
X56335Y-740D01*
X57051D01*
X57713Y-466D01*
X58219Y40D01*
X58493Y702D01*
Y1418D01*
X58219Y2079D01*
X57713Y2585D01*
X57051Y2860D01*
D02*
G37*
G36*
X62169Y2587D02*
X61453D01*
X60791Y2313D01*
X60285Y1807D01*
X60011Y1145D01*
Y429D01*
X60285Y-232D01*
X60791Y-739D01*
X61453Y-1013D01*
X62169D01*
X62831Y-739D01*
X63337Y-232D01*
X63611Y429D01*
Y1145D01*
X63337Y1807D01*
X62831Y2313D01*
X62169Y2587D01*
D02*
G37*
G36*
X84610Y-562D02*
X83894D01*
X83232Y-836D01*
X82726Y-1343D01*
X82452Y-2004D01*
Y-2720D01*
X82726Y-3382D01*
X83197Y-3853D01*
X83216Y-4134D01*
X83197Y-4415D01*
X82726Y-4886D01*
X82452Y-5548D01*
Y-6264D01*
X82726Y-6925D01*
X82955Y-7154D01*
X83196Y-7480D01*
X82955Y-7807D01*
X82726Y-8036D01*
X82452Y-8697D01*
Y-9413D01*
X82726Y-10075D01*
X83232Y-10581D01*
X83894Y-10855D01*
X84610D01*
X85272Y-10581D01*
X85778Y-10075D01*
X86052Y-9413D01*
Y-8697D01*
X85778Y-8036D01*
X85549Y-7807D01*
X85308Y-7480D01*
X85549Y-7154D01*
X85778Y-6925D01*
X86052Y-6264D01*
Y-5548D01*
X85778Y-4886D01*
X85307Y-4415D01*
X85288Y-4134D01*
X85307Y-3853D01*
X85778Y-3382D01*
X85976Y-2903D01*
X86152Y-2887D01*
X86497Y-2953D01*
X86731Y-3520D01*
X87238Y-4026D01*
X87899Y-4300D01*
X88616D01*
X89277Y-4026D01*
X89783Y-3520D01*
X90057Y-2858D01*
Y-2142D01*
X89783Y-1480D01*
X89277Y-974D01*
X88616Y-700D01*
X87899D01*
X87238Y-974D01*
X86731Y-1480D01*
X86533Y-1959D01*
X86357Y-1976D01*
X86013Y-1909D01*
X85778Y-1343D01*
X85272Y-836D01*
X84610Y-562D01*
D02*
G37*
G36*
X93966Y-1579D02*
X93250D01*
X92589Y-1854D01*
X92082Y-2360D01*
X91808Y-3022D01*
Y-3738D01*
X92082Y-4399D01*
X92589Y-4905D01*
X93250Y-5179D01*
X93966D01*
X94628Y-4905D01*
X95134Y-4399D01*
X95408Y-3738D01*
Y-3022D01*
X95134Y-2360D01*
X94628Y-1854D01*
X93966Y-1579D01*
D02*
G37*
G36*
X137957Y-4499D02*
X137240D01*
X136579Y-4773D01*
X136108Y-5244D01*
X135827Y-5263D01*
X135546Y-5244D01*
X135075Y-4773D01*
X134413Y-4499D01*
X133697D01*
X133036Y-4773D01*
X132529Y-5280D01*
X132255Y-5941D01*
Y-6657D01*
X132529Y-7319D01*
X133036Y-7825D01*
X133697Y-8099D01*
X134413D01*
X135075Y-7825D01*
X135546Y-7354D01*
X135827Y-7335D01*
X136108Y-7354D01*
X136579Y-7825D01*
X137240Y-8099D01*
X137957D01*
X138618Y-7825D01*
X139124Y-7319D01*
X139398Y-6657D01*
Y-5941D01*
X139124Y-5280D01*
X138618Y-4773D01*
X137957Y-4499D01*
D02*
G37*
G36*
X75752Y-3909D02*
X75036D01*
X74374Y-4183D01*
X73868Y-4689D01*
X73594Y-5351D01*
Y-6067D01*
X73868Y-6728D01*
X74374Y-7235D01*
X75036Y-7509D01*
X75752D01*
X76413Y-7235D01*
X76920Y-6728D01*
X77194Y-6067D01*
Y-5351D01*
X76920Y-4689D01*
X76413Y-4183D01*
X75752Y-3909D01*
D02*
G37*
G36*
X47799D02*
X47083D01*
X46421Y-4183D01*
X45915Y-4689D01*
X45641Y-5351D01*
Y-6067D01*
X45915Y-6728D01*
X46421Y-7235D01*
X47083Y-7509D01*
X47799D01*
X48461Y-7235D01*
X48967Y-6728D01*
X49241Y-6067D01*
Y-5351D01*
X48967Y-4689D01*
X48461Y-4183D01*
X47799Y-3909D01*
D02*
G37*
G36*
X90516Y-5680D02*
X89799D01*
X89138Y-5954D01*
X88631Y-6461D01*
X88358Y-7122D01*
Y-7838D01*
X88631Y-8500D01*
X89138Y-9006D01*
X89799Y-9280D01*
X90516D01*
X91177Y-9006D01*
X91683Y-8500D01*
X91957Y-7838D01*
Y-7122D01*
X91683Y-6461D01*
X91177Y-5954D01*
X90516Y-5680D01*
D02*
G37*
G36*
X97766Y-8397D02*
X97050D01*
X96388Y-8671D01*
X95882Y-9177D01*
X95608Y-9839D01*
Y-10555D01*
X95882Y-11216D01*
X96388Y-11723D01*
X97050Y-11997D01*
X97766D01*
X98427Y-11723D01*
X98934Y-11216D01*
X99208Y-10555D01*
Y-9839D01*
X98934Y-9177D01*
X98427Y-8671D01*
X97766Y-8397D01*
D02*
G37*
G36*
X150161Y-7438D02*
X149445D01*
X148784Y-7712D01*
X148277Y-8218D01*
X148003Y-8880D01*
Y-9596D01*
X148277Y-10257D01*
X148784Y-10764D01*
X149445Y-11038D01*
X150161D01*
X150823Y-10764D01*
X151243Y-10343D01*
X151648Y-10441D01*
X151743Y-10496D01*
Y-10791D01*
X152017Y-11453D01*
X152524Y-11959D01*
X153185Y-12233D01*
X153901D01*
X154563Y-11959D01*
X155069Y-11453D01*
X155343Y-10791D01*
Y-10075D01*
X155069Y-9414D01*
X154563Y-8907D01*
X153901Y-8633D01*
X153185D01*
X152524Y-8907D01*
X152103Y-9328D01*
X151699Y-9229D01*
X151603Y-9174D01*
Y-8880D01*
X151329Y-8218D01*
X150823Y-7712D01*
X150161Y-7438D01*
D02*
G37*
G36*
X168468Y-8830D02*
X167752D01*
X167091Y-9104D01*
X166584Y-9610D01*
X166310Y-10272D01*
Y-10988D01*
X166584Y-11649D01*
X167091Y-12156D01*
X167752Y-12430D01*
X168468D01*
X169130Y-12156D01*
X169636Y-11649D01*
X169910Y-10988D01*
Y-10272D01*
X169636Y-9610D01*
X169130Y-9104D01*
X168468Y-8830D01*
D02*
G37*
G36*
X214925Y-9617D02*
X214209D01*
X213547Y-9891D01*
X213041Y-10398D01*
X212767Y-11059D01*
Y-11775D01*
X213041Y-12437D01*
X213547Y-12943D01*
X214209Y-13217D01*
X214925D01*
X215586Y-12943D01*
X216093Y-12437D01*
X216367Y-11775D01*
Y-11059D01*
X216093Y-10398D01*
X215586Y-9891D01*
X214925Y-9617D01*
D02*
G37*
G36*
X145043Y-10011D02*
X144327D01*
X143665Y-10285D01*
X143159Y-10791D01*
X142885Y-11453D01*
Y-12169D01*
X143159Y-12831D01*
X143665Y-13337D01*
X144327Y-13611D01*
X145043D01*
X145705Y-13337D01*
X146211Y-12831D01*
X146485Y-12169D01*
Y-11453D01*
X146211Y-10791D01*
X145705Y-10285D01*
X145043Y-10011D01*
D02*
G37*
G36*
X75752D02*
X75036D01*
X74374Y-10285D01*
X73868Y-10791D01*
X73594Y-11453D01*
Y-12169D01*
X73868Y-12831D01*
X74374Y-13337D01*
X75036Y-13611D01*
X75752D01*
X76413Y-13337D01*
X76920Y-12831D01*
X77194Y-12169D01*
Y-11453D01*
X76920Y-10791D01*
X76413Y-10285D01*
X75752Y-10011D01*
D02*
G37*
G36*
X66500D02*
X65784D01*
X65122Y-10285D01*
X64616Y-10791D01*
X64342Y-11453D01*
Y-12169D01*
X64616Y-12831D01*
X65122Y-13337D01*
X65784Y-13611D01*
X66500D01*
X67161Y-13337D01*
X67668Y-12831D01*
X67942Y-12169D01*
Y-11453D01*
X67668Y-10791D01*
X67161Y-10285D01*
X66500Y-10011D01*
D02*
G37*
G36*
X61775D02*
X61059D01*
X60398Y-10285D01*
X59891Y-10791D01*
X59617Y-11453D01*
Y-12169D01*
X59891Y-12831D01*
X60398Y-13337D01*
X61059Y-13611D01*
X61775D01*
X62437Y-13337D01*
X62943Y-12831D01*
X63217Y-12169D01*
Y-11453D01*
X62943Y-10791D01*
X62437Y-10285D01*
X61775Y-10011D01*
D02*
G37*
G36*
X57051D02*
X56335D01*
X55673Y-10285D01*
X55167Y-10791D01*
X54893Y-11453D01*
Y-12169D01*
X55167Y-12831D01*
X55673Y-13337D01*
X56335Y-13611D01*
X57051D01*
X57713Y-13337D01*
X58219Y-12831D01*
X58493Y-12169D01*
Y-11453D01*
X58219Y-10791D01*
X57713Y-10285D01*
X57051Y-10011D01*
D02*
G37*
G36*
X47799D02*
X47083D01*
X46421Y-10285D01*
X45915Y-10791D01*
X45641Y-11453D01*
Y-12169D01*
X45915Y-12831D01*
X46421Y-13337D01*
X47083Y-13611D01*
X47799D01*
X48461Y-13337D01*
X48967Y-12831D01*
X49241Y-12169D01*
Y-11453D01*
X48967Y-10791D01*
X48461Y-10285D01*
X47799Y-10011D01*
D02*
G37*
G36*
X127523Y-10798D02*
X126807D01*
X126146Y-11073D01*
X125639Y-11579D01*
X125365Y-12240D01*
Y-12957D01*
X125639Y-13618D01*
X126146Y-14124D01*
X126807Y-14398D01*
X127523D01*
X128185Y-14124D01*
X128691Y-13618D01*
X128965Y-12957D01*
Y-12240D01*
X128691Y-11579D01*
X128185Y-11073D01*
X127523Y-10798D01*
D02*
G37*
G36*
X162957Y-7649D02*
X162240D01*
X161579Y-7923D01*
X161073Y-8429D01*
X160798Y-9091D01*
Y-9807D01*
X161073Y-10468D01*
X161579Y-10975D01*
X161756Y-11048D01*
Y-11590D01*
X161579Y-11663D01*
X161073Y-12169D01*
X160798Y-12831D01*
Y-13547D01*
X161073Y-14209D01*
X161579Y-14715D01*
X162240Y-14989D01*
X162957D01*
X163618Y-14715D01*
X164124Y-14209D01*
X164398Y-13547D01*
Y-12831D01*
X164124Y-12169D01*
X163618Y-11663D01*
X163441Y-11590D01*
Y-11048D01*
X163618Y-10975D01*
X164124Y-10468D01*
X164398Y-9807D01*
Y-9091D01*
X164124Y-8429D01*
X163618Y-7923D01*
X162957Y-7649D01*
D02*
G37*
G36*
X212169Y-14735D02*
X211453D01*
X210791Y-15010D01*
X210285Y-15516D01*
X210011Y-16177D01*
Y-16894D01*
X210285Y-17555D01*
X210791Y-18061D01*
X211453Y-18335D01*
X212169D01*
X212831Y-18061D01*
X213337Y-17555D01*
X213611Y-16894D01*
Y-16177D01*
X213337Y-15516D01*
X212831Y-15010D01*
X212169Y-14735D01*
D02*
G37*
G36*
X66500D02*
X65784D01*
X65122Y-15010D01*
X64616Y-15516D01*
X64342Y-16177D01*
Y-16894D01*
X64616Y-17555D01*
X65122Y-18061D01*
X65784Y-18335D01*
X66500D01*
X67161Y-18061D01*
X67668Y-17555D01*
X67942Y-16894D01*
Y-16177D01*
X67668Y-15516D01*
X67161Y-15010D01*
X66500Y-14735D01*
D02*
G37*
G36*
X61775D02*
X61059D01*
X60398Y-15010D01*
X59891Y-15516D01*
X59617Y-16177D01*
Y-16894D01*
X59891Y-17555D01*
X60398Y-18061D01*
X61059Y-18335D01*
X61775D01*
X62437Y-18061D01*
X62943Y-17555D01*
X63217Y-16894D01*
Y-16177D01*
X62943Y-15516D01*
X62437Y-15010D01*
X61775Y-14735D01*
D02*
G37*
G36*
X57051D02*
X56335D01*
X55673Y-15010D01*
X55167Y-15516D01*
X54893Y-16177D01*
Y-16894D01*
X55167Y-17555D01*
X55673Y-18061D01*
X56335Y-18335D01*
X57051D01*
X57713Y-18061D01*
X58219Y-17555D01*
X58493Y-16894D01*
Y-16177D01*
X58219Y-15516D01*
X57713Y-15010D01*
X57051Y-14735D01*
D02*
G37*
G36*
X119256Y-15129D02*
X118540D01*
X117878Y-15403D01*
X117372Y-15910D01*
X117098Y-16571D01*
Y-17287D01*
X117372Y-17949D01*
X117878Y-18455D01*
X118540Y-18729D01*
X119256D01*
X119917Y-18455D01*
X120424Y-17949D01*
X120698Y-17287D01*
Y-16571D01*
X120424Y-15910D01*
X119917Y-15403D01*
X119256Y-15129D01*
D02*
G37*
G36*
X86211Y-11980D02*
X85495D01*
X84834Y-12254D01*
X84327Y-12760D01*
X84053Y-13421D01*
Y-14138D01*
X84327Y-14799D01*
X84543Y-15014D01*
X84783Y-15368D01*
X84543Y-15668D01*
X84301Y-15910D01*
X84027Y-16571D01*
Y-17287D01*
X84301Y-17949D01*
X84807Y-18455D01*
X85469Y-18729D01*
X86185D01*
X86846Y-18455D01*
X87353Y-17949D01*
X87627Y-17287D01*
Y-16571D01*
X87353Y-15910D01*
X87137Y-15694D01*
X86897Y-15340D01*
X87137Y-15041D01*
X87379Y-14799D01*
X87653Y-14138D01*
Y-13421D01*
X87379Y-12760D01*
X86873Y-12254D01*
X86211Y-11980D01*
D02*
G37*
G36*
X157051Y-16310D02*
X156335D01*
X155673Y-16584D01*
X155167Y-17091D01*
X154893Y-17752D01*
Y-18468D01*
X155167Y-19130D01*
X155673Y-19636D01*
X156335Y-19910D01*
X157051D01*
X157712Y-19636D01*
X158219Y-19130D01*
X158493Y-18468D01*
Y-17752D01*
X158219Y-17091D01*
X157712Y-16584D01*
X157051Y-16310D01*
D02*
G37*
G36*
X105640Y-17491D02*
X104924D01*
X104262Y-17765D01*
X103756Y-18272D01*
X103482Y-18933D01*
Y-19649D01*
X103756Y-20311D01*
X104262Y-20817D01*
X104924Y-21091D01*
X105640D01*
X106301Y-20817D01*
X106808Y-20311D01*
X107082Y-19649D01*
Y-18933D01*
X106808Y-18272D01*
X106301Y-17765D01*
X105640Y-17491D01*
D02*
G37*
G36*
X168468Y-18279D02*
X167752D01*
X167091Y-18553D01*
X166584Y-19059D01*
X166310Y-19721D01*
Y-20437D01*
X166584Y-21098D01*
X167091Y-21605D01*
X167752Y-21879D01*
X168468D01*
X169130Y-21605D01*
X169636Y-21098D01*
X169910Y-20437D01*
Y-19721D01*
X169636Y-19059D01*
X169130Y-18553D01*
X168468Y-18279D01*
D02*
G37*
G36*
X211382Y-19460D02*
X210666D01*
X210004Y-19734D01*
X209498Y-20240D01*
X209224Y-20902D01*
Y-21618D01*
X209498Y-22279D01*
X210004Y-22786D01*
X210666Y-23060D01*
X211382D01*
X212043Y-22786D01*
X212550Y-22279D01*
X212824Y-21618D01*
Y-20902D01*
X212550Y-20240D01*
X212043Y-19734D01*
X211382Y-19460D01*
D02*
G37*
G36*
X66500D02*
X65784D01*
X65122Y-19734D01*
X64616Y-20240D01*
X64342Y-20902D01*
Y-21618D01*
X64616Y-22279D01*
X65122Y-22786D01*
X65784Y-23060D01*
X66500D01*
X67161Y-22786D01*
X67668Y-22279D01*
X67942Y-21618D01*
Y-20902D01*
X67668Y-20240D01*
X67161Y-19734D01*
X66500Y-19460D01*
D02*
G37*
G36*
X61775D02*
X61059D01*
X60398Y-19734D01*
X59891Y-20240D01*
X59617Y-20902D01*
Y-21618D01*
X59891Y-22279D01*
X60398Y-22786D01*
X61059Y-23060D01*
X61775D01*
X62437Y-22786D01*
X62943Y-22279D01*
X63217Y-21618D01*
Y-20902D01*
X62943Y-20240D01*
X62437Y-19734D01*
X61775Y-19460D01*
D02*
G37*
G36*
X117287Y-19853D02*
X116571D01*
X115910Y-20128D01*
X115403Y-20634D01*
X115129Y-21295D01*
Y-22012D01*
X115403Y-22673D01*
X115910Y-23179D01*
X116571Y-23453D01*
X117287D01*
X117949Y-23179D01*
X118455Y-22673D01*
X118729Y-22012D01*
Y-21295D01*
X118455Y-20634D01*
X117949Y-20128D01*
X117287Y-19853D01*
D02*
G37*
G36*
X138794Y-19600D02*
X137801D01*
X136883Y-19980D01*
X136181Y-20682D01*
X135801Y-21600D01*
Y-22593D01*
X136181Y-23510D01*
X136883Y-24212D01*
X137801Y-24592D01*
X138794D01*
X139711Y-24212D01*
X140413Y-23510D01*
X140793Y-22593D01*
Y-21600D01*
X140413Y-20682D01*
X139711Y-19980D01*
X138794Y-19600D01*
D02*
G37*
G36*
X216894Y-23397D02*
X216177D01*
X215516Y-23671D01*
X215009Y-24177D01*
X214735Y-24839D01*
Y-25555D01*
X215009Y-26217D01*
X215516Y-26723D01*
X216177Y-26997D01*
X216894D01*
X217555Y-26723D01*
X218061Y-26217D01*
X218335Y-25555D01*
Y-24839D01*
X218061Y-24177D01*
X217555Y-23671D01*
X216894Y-23397D01*
D02*
G37*
G36*
X608764Y-68279D02*
X608047D01*
X607386Y-68553D01*
X606880Y-69059D01*
X606605Y-69721D01*
Y-70437D01*
X606880Y-71098D01*
X607386Y-71605D01*
X608047Y-71879D01*
X608764D01*
X609425Y-71605D01*
X609932Y-71098D01*
X610206Y-70437D01*
Y-69721D01*
X609932Y-69059D01*
X609425Y-68553D01*
X608764Y-68279D01*
D02*
G37*
G36*
X608626Y-82452D02*
X607910D01*
X607248Y-82726D01*
X606742Y-83232D01*
X606468Y-83894D01*
Y-84610D01*
X606742Y-85272D01*
X607248Y-85778D01*
X607910Y-86052D01*
X608626D01*
X609287Y-85778D01*
X609794Y-85272D01*
X610068Y-84610D01*
Y-83894D01*
X609794Y-83232D01*
X609287Y-82726D01*
X608626Y-82452D01*
D02*
G37*
G36*
X603901Y-85995D02*
X603185D01*
X602524Y-86269D01*
X602017Y-86776D01*
X601743Y-87437D01*
Y-88153D01*
X602017Y-88815D01*
X602524Y-89321D01*
X603185Y-89595D01*
X603901D01*
X604563Y-89321D01*
X605069Y-88815D01*
X605343Y-88153D01*
Y-87437D01*
X605069Y-86776D01*
X604563Y-86269D01*
X603901Y-85995D01*
D02*
G37*
G36*
X598755Y-86488D02*
X598039D01*
X597377Y-86761D01*
X596871Y-87268D01*
X596597Y-87929D01*
Y-88645D01*
X596871Y-89307D01*
X597377Y-89813D01*
X598039Y-90087D01*
X598755D01*
X599416Y-89813D01*
X599923Y-89307D01*
X600197Y-88645D01*
Y-87929D01*
X599923Y-87268D01*
X599416Y-86761D01*
X598755Y-86488D01*
D02*
G37*
G36*
X613764Y-87694D02*
X613048D01*
X612386Y-87968D01*
X611880Y-88475D01*
X611606Y-89136D01*
Y-89852D01*
X611880Y-90514D01*
X612386Y-91020D01*
X613048Y-91294D01*
X613764D01*
X614425Y-91020D01*
X614931Y-90514D01*
X615205Y-89852D01*
Y-89136D01*
X614931Y-88475D01*
X614425Y-87968D01*
X613764Y-87694D01*
D02*
G37*
G36*
X602463Y-97309D02*
X601747D01*
X601085Y-97583D01*
X600579Y-98090D01*
X600305Y-98751D01*
Y-99467D01*
X600579Y-100129D01*
X601085Y-100635D01*
X601747Y-100909D01*
X602463D01*
X603124Y-100635D01*
X603631Y-100129D01*
X603905Y-99467D01*
Y-98751D01*
X603631Y-98090D01*
X603124Y-97583D01*
X602463Y-97309D01*
D02*
G37*
G36*
X619969Y-94236D02*
X618928D01*
X617923Y-94506D01*
X617022Y-95026D01*
X616286Y-95762D01*
X615765Y-96663D01*
X615496Y-97669D01*
Y-98709D01*
X615765Y-99715D01*
X616286Y-100616D01*
X617022Y-101352D01*
X617923Y-101872D01*
X618928Y-102142D01*
X619969D01*
X620974Y-101872D01*
X621876Y-101352D01*
X622612Y-100616D01*
X623132Y-99715D01*
X623402Y-98709D01*
Y-97669D01*
X623132Y-96663D01*
X622612Y-95762D01*
X621876Y-95026D01*
X620974Y-94506D01*
X619969Y-94236D01*
D02*
G37*
G36*
X613402D02*
X605496D01*
Y-102142D01*
X613402D01*
Y-94236D01*
D02*
G37*
G36*
X597602Y-106861D02*
X596886D01*
X596224Y-107135D01*
X595718Y-107642D01*
X595444Y-108303D01*
Y-109019D01*
X595718Y-109681D01*
X596224Y-110187D01*
X596886Y-110461D01*
X597602D01*
X598264Y-110187D01*
X598770Y-109681D01*
X599044Y-109019D01*
Y-108303D01*
X598770Y-107642D01*
X598264Y-107135D01*
X597602Y-106861D01*
D02*
G37*
G36*
X619969Y-104236D02*
X618928D01*
X617923Y-104506D01*
X617022Y-105026D01*
X616286Y-105762D01*
X615765Y-106663D01*
X615496Y-107669D01*
Y-108709D01*
X615765Y-109715D01*
X616286Y-110616D01*
X617022Y-111352D01*
X617923Y-111872D01*
X618928Y-112142D01*
X619969D01*
X620974Y-111872D01*
X621876Y-111352D01*
X622612Y-110616D01*
X623132Y-109715D01*
X623402Y-108709D01*
Y-107669D01*
X623132Y-106663D01*
X622612Y-105762D01*
X621876Y-105026D01*
X620974Y-104506D01*
X619969Y-104236D01*
D02*
G37*
G36*
X609969D02*
X608928D01*
X607923Y-104506D01*
X607022Y-105026D01*
X606286Y-105762D01*
X605765Y-106663D01*
X605496Y-107669D01*
Y-108709D01*
X605765Y-109715D01*
X606286Y-110616D01*
X607022Y-111352D01*
X607923Y-111872D01*
X608928Y-112142D01*
X609969D01*
X610975Y-111872D01*
X611876Y-111352D01*
X612612Y-110616D01*
X613132Y-109715D01*
X613402Y-108709D01*
Y-107669D01*
X613132Y-106663D01*
X612612Y-105762D01*
X611876Y-105026D01*
X610975Y-104506D01*
X609969Y-104236D01*
D02*
G37*
G36*
X593271Y-114735D02*
X592555D01*
X591894Y-115009D01*
X591387Y-115516D01*
X591113Y-116177D01*
Y-116893D01*
X591387Y-117555D01*
X591894Y-118061D01*
X592555Y-118335D01*
X593271D01*
X593933Y-118061D01*
X594439Y-117555D01*
X594713Y-116893D01*
Y-116177D01*
X594439Y-115516D01*
X593933Y-115009D01*
X593271Y-114735D01*
D02*
G37*
G36*
X619969Y-114236D02*
X618928D01*
X617923Y-114506D01*
X617022Y-115026D01*
X616286Y-115762D01*
X615765Y-116663D01*
X615496Y-117669D01*
Y-118709D01*
X615765Y-119715D01*
X616286Y-120616D01*
X617022Y-121352D01*
X617923Y-121872D01*
X618928Y-122142D01*
X619969D01*
X620974Y-121872D01*
X621876Y-121352D01*
X622612Y-120616D01*
X623132Y-119715D01*
X623402Y-118709D01*
Y-117669D01*
X623132Y-116663D01*
X622612Y-115762D01*
X621876Y-115026D01*
X620974Y-114506D01*
X619969Y-114236D01*
D02*
G37*
G36*
X609969D02*
X608928D01*
X607923Y-114506D01*
X607022Y-115026D01*
X606286Y-115762D01*
X605765Y-116663D01*
X605496Y-117669D01*
Y-118709D01*
X605765Y-119715D01*
X606286Y-120616D01*
X607022Y-121352D01*
X607923Y-121872D01*
X608928Y-122142D01*
X609969D01*
X610975Y-121872D01*
X611876Y-121352D01*
X612612Y-120616D01*
X613132Y-119715D01*
X613402Y-118709D01*
Y-117669D01*
X613132Y-116663D01*
X612612Y-115762D01*
X611876Y-115026D01*
X610975Y-114506D01*
X609969Y-114236D01*
D02*
G37*
G36*
X619969Y-124236D02*
X618928D01*
X617923Y-124506D01*
X617022Y-125026D01*
X616286Y-125762D01*
X615765Y-126663D01*
X615496Y-127669D01*
Y-128709D01*
X615765Y-129715D01*
X616286Y-130616D01*
X617022Y-131352D01*
X617923Y-131872D01*
X618928Y-132142D01*
X619969D01*
X620974Y-131872D01*
X621876Y-131352D01*
X622612Y-130616D01*
X623132Y-129715D01*
X623402Y-128709D01*
Y-127669D01*
X623132Y-126663D01*
X622612Y-125762D01*
X621876Y-125026D01*
X620974Y-124506D01*
X619969Y-124236D01*
D02*
G37*
G36*
X609969D02*
X608928D01*
X607923Y-124506D01*
X607022Y-125026D01*
X606286Y-125762D01*
X605765Y-126663D01*
X605496Y-127669D01*
Y-128709D01*
X605765Y-129715D01*
X606286Y-130616D01*
X607022Y-131352D01*
X607923Y-131872D01*
X608928Y-132142D01*
X609969D01*
X610975Y-131872D01*
X611876Y-131352D01*
X612612Y-130616D01*
X613132Y-129715D01*
X613402Y-128709D01*
Y-127669D01*
X613132Y-126663D01*
X612612Y-125762D01*
X611876Y-125026D01*
X610975Y-124506D01*
X609969Y-124236D01*
D02*
G37*
G36*
X594846Y-130877D02*
X594130D01*
X593469Y-131151D01*
X592962Y-131658D01*
X592688Y-132319D01*
Y-133035D01*
X592962Y-133697D01*
X593469Y-134203D01*
X594130Y-134477D01*
X594846D01*
X595508Y-134203D01*
X596014Y-133697D01*
X596288Y-133035D01*
Y-132319D01*
X596014Y-131658D01*
X595508Y-131151D01*
X594846Y-130877D01*
D02*
G37*
G36*
X619969Y-134236D02*
X618928D01*
X617923Y-134506D01*
X617022Y-135026D01*
X616286Y-135762D01*
X615765Y-136663D01*
X615496Y-137669D01*
Y-138709D01*
X615765Y-139715D01*
X616286Y-140616D01*
X617022Y-141352D01*
X617923Y-141872D01*
X618928Y-142142D01*
X619969D01*
X620974Y-141872D01*
X621876Y-141352D01*
X622612Y-140616D01*
X623132Y-139715D01*
X623402Y-138709D01*
Y-137669D01*
X623132Y-136663D01*
X622612Y-135762D01*
X621876Y-135026D01*
X620974Y-134506D01*
X619969Y-134236D01*
D02*
G37*
G36*
X609969D02*
X608928D01*
X607923Y-134506D01*
X607022Y-135026D01*
X606286Y-135762D01*
X605765Y-136663D01*
X605496Y-137669D01*
Y-138709D01*
X605765Y-139715D01*
X606286Y-140616D01*
X607022Y-141352D01*
X607923Y-141872D01*
X608928Y-142142D01*
X609969D01*
X610975Y-141872D01*
X611876Y-141352D01*
X612612Y-140616D01*
X613132Y-139715D01*
X613402Y-138709D01*
Y-137669D01*
X613132Y-136663D01*
X612612Y-135762D01*
X611876Y-135026D01*
X610975Y-134506D01*
X609969Y-134236D01*
D02*
G37*
G36*
X591697Y-142688D02*
X590980D01*
X590319Y-142962D01*
X589813Y-143469D01*
X589539Y-144130D01*
Y-144846D01*
X589813Y-145508D01*
X590319Y-146014D01*
X590980Y-146288D01*
X591697D01*
X592358Y-146014D01*
X592865Y-145508D01*
X593139Y-144846D01*
Y-144130D01*
X592865Y-143469D01*
X592358Y-142962D01*
X591697Y-142688D01*
D02*
G37*
G36*
X582523Y-162098D02*
X581807D01*
X581146Y-162372D01*
X580639Y-162878D01*
X580365Y-163540D01*
Y-164256D01*
X580639Y-164917D01*
X581146Y-165424D01*
X581807Y-165698D01*
X582523D01*
X583185Y-165424D01*
X583691Y-164917D01*
X583965Y-164256D01*
Y-163540D01*
X583691Y-162878D01*
X583185Y-162372D01*
X582523Y-162098D01*
D02*
G37*
G36*
X582248Y-172216D02*
X581532D01*
X580870Y-172490D01*
X580364Y-172996D01*
X580090Y-173658D01*
Y-174374D01*
X580364Y-175035D01*
X580870Y-175542D01*
X581532Y-175816D01*
X582248D01*
X582909Y-175542D01*
X583416Y-175035D01*
X583690Y-174374D01*
Y-173658D01*
X583416Y-172996D01*
X582909Y-172490D01*
X582248Y-172216D01*
D02*
G37*
G36*
X591697Y-187964D02*
X590980D01*
X590319Y-188238D01*
X589813Y-188744D01*
X589539Y-189406D01*
Y-190122D01*
X589813Y-190783D01*
X590319Y-191290D01*
X590980Y-191564D01*
X591697D01*
X592358Y-191290D01*
X592865Y-190783D01*
X593139Y-190122D01*
Y-189406D01*
X592865Y-188744D01*
X592358Y-188238D01*
X591697Y-187964D01*
D02*
G37*
G36*
X589728Y-199775D02*
X589012D01*
X588350Y-200049D01*
X587844Y-200555D01*
X587570Y-201217D01*
Y-201933D01*
X587844Y-202594D01*
X588350Y-203101D01*
X589012Y-203375D01*
X589728D01*
X590390Y-203101D01*
X590896Y-202594D01*
X591170Y-201933D01*
Y-201217D01*
X590896Y-200555D01*
X590390Y-200049D01*
X589728Y-199775D01*
D02*
G37*
G36*
X589280Y-204662D02*
X588564D01*
X587903Y-204936D01*
X587396Y-205442D01*
X587122Y-206104D01*
Y-206820D01*
X587396Y-207482D01*
X587903Y-207988D01*
X588564Y-208262D01*
X589280D01*
X589942Y-207988D01*
X590448Y-207482D01*
X590722Y-206820D01*
Y-206104D01*
X590448Y-205442D01*
X589942Y-204936D01*
X589280Y-204662D01*
D02*
G37*
G36*
X589728Y-211192D02*
X589012D01*
X588350Y-211466D01*
X587844Y-211972D01*
X587570Y-212634D01*
Y-213350D01*
X587844Y-214012D01*
X588350Y-214518D01*
X589012Y-214792D01*
X589728D01*
X590390Y-214518D01*
X590896Y-214012D01*
X591170Y-213350D01*
Y-212634D01*
X590896Y-211972D01*
X590390Y-211466D01*
X589728Y-211192D01*
D02*
G37*
G36*
X590546Y-219361D02*
X589830D01*
X589169Y-219636D01*
X588662Y-220142D01*
X588388Y-220803D01*
Y-221519D01*
X588662Y-222181D01*
X589169Y-222687D01*
X589830Y-222961D01*
X590546D01*
X591208Y-222687D01*
X591714Y-222181D01*
X591988Y-221519D01*
Y-220803D01*
X591714Y-220142D01*
X591208Y-219636D01*
X590546Y-219361D01*
D02*
G37*
G36*
X612169Y-219460D02*
X611453D01*
X610791Y-219734D01*
X610285Y-220240D01*
X610011Y-220902D01*
Y-221618D01*
X610285Y-222280D01*
X610791Y-222786D01*
X611453Y-223060D01*
X612169D01*
X612831Y-222786D01*
X613337Y-222280D01*
X613611Y-221618D01*
Y-220902D01*
X613337Y-220240D01*
X612831Y-219734D01*
X612169Y-219460D01*
D02*
G37*
G36*
X617287Y-224184D02*
X616571D01*
X615909Y-224458D01*
X615403Y-224965D01*
X615129Y-225626D01*
Y-226342D01*
X615403Y-227004D01*
X615909Y-227510D01*
X616571Y-227784D01*
X617287D01*
X617949Y-227510D01*
X618455Y-227004D01*
X618729Y-226342D01*
Y-225626D01*
X618455Y-224965D01*
X617949Y-224458D01*
X617287Y-224184D01*
D02*
G37*
G36*
X603508Y-234146D02*
X602792D01*
X602130Y-234420D01*
X601624Y-234926D01*
X601350Y-235588D01*
Y-236304D01*
X601624Y-236965D01*
X602130Y-237472D01*
X602792Y-237746D01*
X603508D01*
X604169Y-237472D01*
X604676Y-236965D01*
X604950Y-236304D01*
Y-235588D01*
X604676Y-234926D01*
X604169Y-234420D01*
X603508Y-234146D01*
D02*
G37*
G36*
X596421Y-238095D02*
X595705D01*
X595043Y-238369D01*
X594537Y-238875D01*
X594263Y-239537D01*
Y-240253D01*
X594537Y-240915D01*
X594567Y-240945D01*
X594537Y-240975D01*
X594263Y-241637D01*
Y-242353D01*
X594537Y-243015D01*
X595043Y-243521D01*
X595705Y-243795D01*
X596421D01*
X597083Y-243521D01*
X597589Y-243015D01*
X597863Y-242353D01*
Y-241637D01*
X597589Y-240975D01*
X597559Y-240945D01*
X597589Y-240915D01*
X597863Y-240253D01*
Y-239537D01*
X597589Y-238875D01*
X597083Y-238369D01*
X596421Y-238095D01*
D02*
G37*
G36*
X604674Y-244799D02*
X603958D01*
X603297Y-245074D01*
X602790Y-245580D01*
X602516Y-246241D01*
Y-246958D01*
X602790Y-247619D01*
X603297Y-248126D01*
X603958Y-248399D01*
X604674D01*
X605336Y-248126D01*
X605842Y-247619D01*
X606116Y-246958D01*
Y-246241D01*
X605842Y-245580D01*
X605336Y-245074D01*
X604674Y-244799D01*
D02*
G37*
G36*
X597223Y-264596D02*
X596506D01*
X595845Y-264870D01*
X595815Y-264900D01*
X595784Y-264870D01*
X595122Y-264596D01*
X594406D01*
X593745Y-264870D01*
X593238Y-265376D01*
X592965Y-266038D01*
Y-266754D01*
X593238Y-267416D01*
X593745Y-267922D01*
X594406Y-268196D01*
X595122D01*
X595784Y-267922D01*
X595815Y-267892D01*
X595845Y-267922D01*
X596506Y-268196D01*
X597223D01*
X597884Y-267922D01*
X598390Y-267416D01*
X598665Y-266754D01*
Y-266038D01*
X598390Y-265376D01*
X597884Y-264870D01*
X597223Y-264596D01*
D02*
G37*
G36*
X599403Y-273232D02*
X598686D01*
X598025Y-273506D01*
X597518Y-274012D01*
X597244Y-274674D01*
Y-275390D01*
X597518Y-276051D01*
X598025Y-276557D01*
X598686Y-276832D01*
X599403D01*
X600064Y-276557D01*
X600570Y-276051D01*
X600844Y-275390D01*
Y-274674D01*
X600570Y-274012D01*
X600064Y-273506D01*
X599403Y-273232D01*
D02*
G37*
G36*
X593665Y-290326D02*
X592949D01*
X592287Y-290600D01*
X591781Y-291106D01*
X591507Y-291768D01*
Y-292484D01*
X591781Y-293146D01*
X592287Y-293652D01*
X592949Y-293926D01*
X593665D01*
X594327Y-293652D01*
X594833Y-293146D01*
X595107Y-292484D01*
Y-291768D01*
X594833Y-291106D01*
X594327Y-290600D01*
X593665Y-290326D01*
D02*
G37*
G36*
X576736Y-295936D02*
X576020D01*
X575358Y-296210D01*
X574852Y-296717D01*
X574578Y-297378D01*
Y-298094D01*
X574852Y-298756D01*
X575358Y-299262D01*
X576020Y-299536D01*
X576736D01*
X577398Y-299262D01*
X577904Y-298756D01*
X578178Y-298094D01*
Y-297378D01*
X577904Y-296717D01*
X577398Y-296210D01*
X576736Y-295936D01*
D02*
G37*
G36*
X570437Y-308121D02*
X569721D01*
X569059Y-308395D01*
X568553Y-308901D01*
X568279Y-309562D01*
Y-310279D01*
X568553Y-310940D01*
X569059Y-311446D01*
X569721Y-311721D01*
X570437D01*
X571098Y-311446D01*
X571605Y-310940D01*
X571879Y-310279D01*
Y-309562D01*
X571605Y-308901D01*
X571098Y-308395D01*
X570437Y-308121D01*
D02*
G37*
G36*
X599256Y-311507D02*
X598540D01*
X597878Y-311781D01*
X597372Y-312287D01*
X597098Y-312949D01*
Y-313665D01*
X597372Y-314327D01*
X597878Y-314833D01*
X598540Y-315107D01*
X599256D01*
X599917Y-314833D01*
X600424Y-314327D01*
X600698Y-313665D01*
Y-312949D01*
X600424Y-312287D01*
X599917Y-311781D01*
X599256Y-311507D01*
D02*
G37*
G36*
X582923Y-320073D02*
X581192D01*
X579482Y-320344D01*
X577835Y-320879D01*
X576292Y-321665D01*
X574892Y-322682D01*
X573667Y-323907D01*
X572649Y-325308D01*
X571863Y-326850D01*
X571328Y-328497D01*
X571058Y-330207D01*
Y-331939D01*
X571328Y-333649D01*
X571863Y-335295D01*
X572649Y-336838D01*
X573667Y-338239D01*
X574892Y-339463D01*
X576292Y-340481D01*
X577835Y-341267D01*
X579482Y-341802D01*
X581192Y-342073D01*
X582923D01*
X584633Y-341802D01*
X586280Y-341267D01*
X587823Y-340481D01*
X589223Y-339463D01*
X590448Y-338239D01*
X591466Y-336838D01*
X592252Y-335295D01*
X592787Y-333649D01*
X593057Y-331939D01*
Y-330207D01*
X592787Y-328497D01*
X592252Y-326850D01*
X591466Y-325308D01*
X590448Y-323907D01*
X589223Y-322682D01*
X587823Y-321665D01*
X586280Y-320879D01*
X584633Y-320344D01*
X582923Y-320073D01*
D02*
G37*
G36*
X415130Y-351473D02*
X414414D01*
X413753Y-351747D01*
X413246Y-352254D01*
X412972Y-352915D01*
Y-353631D01*
X413246Y-354293D01*
X413753Y-354799D01*
X414414Y-355073D01*
X415130D01*
X415792Y-354799D01*
X416298Y-354293D01*
X416572Y-353631D01*
Y-352915D01*
X416298Y-352254D01*
X415792Y-351747D01*
X415130Y-351473D01*
D02*
G37*
G36*
X598941Y-351507D02*
X598225D01*
X597563Y-351781D01*
X597057Y-352288D01*
X596783Y-352949D01*
Y-353665D01*
X597057Y-354327D01*
X597563Y-354833D01*
X598225Y-355107D01*
X598941D01*
X599602Y-354833D01*
X600109Y-354327D01*
X600383Y-353665D01*
Y-352949D01*
X600109Y-352288D01*
X599602Y-351781D01*
X598941Y-351507D01*
D02*
G37*
G36*
X544076Y-351740D02*
X543360D01*
X542699Y-352014D01*
X542192Y-352521D01*
X541918Y-353182D01*
Y-353898D01*
X542192Y-354560D01*
X542699Y-355066D01*
X543360Y-355340D01*
X544076D01*
X544738Y-355066D01*
X545244Y-354560D01*
X545518Y-353898D01*
Y-353182D01*
X545244Y-352521D01*
X544738Y-352014D01*
X544076Y-351740D01*
D02*
G37*
G36*
X499660Y-351937D02*
X498944D01*
X498282Y-352211D01*
X497776Y-352718D01*
X497502Y-353379D01*
Y-354095D01*
X497776Y-354757D01*
X498282Y-355263D01*
X498944Y-355537D01*
X499660D01*
X500321Y-355263D01*
X500828Y-354757D01*
X501102Y-354095D01*
Y-353379D01*
X500828Y-352718D01*
X500321Y-352211D01*
X499660Y-351937D01*
D02*
G37*
G36*
X461258Y-352261D02*
X460542D01*
X459880Y-352535D01*
X459374Y-353041D01*
X459100Y-353703D01*
Y-354419D01*
X459374Y-355080D01*
X459880Y-355587D01*
X460542Y-355861D01*
X461258D01*
X461919Y-355587D01*
X462426Y-355080D01*
X462700Y-354419D01*
Y-353703D01*
X462426Y-353041D01*
X461919Y-352535D01*
X461258Y-352261D01*
D02*
G37*
G36*
X449508Y-354032D02*
X448792D01*
X448131Y-354306D01*
X447624Y-354813D01*
X447350Y-355474D01*
Y-356190D01*
X447624Y-356852D01*
X448131Y-357358D01*
X448792Y-357632D01*
X449508D01*
X450170Y-357358D01*
X450676Y-356852D01*
X450950Y-356190D01*
Y-355474D01*
X450676Y-354813D01*
X450170Y-354306D01*
X449508Y-354032D01*
D02*
G37*
G36*
X561688Y-354299D02*
X560972D01*
X560311Y-354573D01*
X559804Y-355080D01*
X559530Y-355741D01*
Y-356457D01*
X559804Y-357119D01*
X560311Y-357625D01*
X560972Y-357899D01*
X561688D01*
X562350Y-357625D01*
X562856Y-357119D01*
X563130Y-356457D01*
Y-355741D01*
X562856Y-355080D01*
X562350Y-354573D01*
X561688Y-354299D01*
D02*
G37*
G36*
X534289Y-354496D02*
X533572D01*
X532911Y-354770D01*
X532405Y-355277D01*
X532131Y-355938D01*
Y-356654D01*
X532405Y-357316D01*
X532911Y-357822D01*
X533572Y-358096D01*
X534289D01*
X534950Y-357822D01*
X535457Y-357316D01*
X535731Y-356654D01*
Y-355938D01*
X535457Y-355277D01*
X534950Y-354770D01*
X534289Y-354496D01*
D02*
G37*
G36*
X493592Y-354820D02*
X492876D01*
X492214Y-355094D01*
X491708Y-355600D01*
X491434Y-356262D01*
Y-356978D01*
X491708Y-357639D01*
X492214Y-358146D01*
X492876Y-358420D01*
X493592D01*
X494254Y-358146D01*
X494760Y-357639D01*
X495034Y-356978D01*
Y-356262D01*
X494760Y-355600D01*
X494254Y-355094D01*
X493592Y-354820D01*
D02*
G37*
G36*
X579430Y-354890D02*
X578714D01*
X578052Y-355164D01*
X577546Y-355670D01*
X577272Y-356332D01*
Y-357048D01*
X577546Y-357710D01*
X578052Y-358216D01*
X578714Y-358490D01*
X579430D01*
X580091Y-358216D01*
X580598Y-357710D01*
X580872Y-357048D01*
Y-356332D01*
X580598Y-355670D01*
X580091Y-355164D01*
X579430Y-354890D01*
D02*
G37*
G36*
X214531Y-77334D02*
X213815D01*
X213154Y-77608D01*
X212647Y-78114D01*
X212373Y-78776D01*
Y-79492D01*
X212647Y-80154D01*
X213154Y-80660D01*
X213815Y-80934D01*
X214531D01*
X215193Y-80660D01*
X215699Y-80154D01*
X215973Y-79492D01*
Y-78776D01*
X215699Y-78114D01*
X215193Y-77608D01*
X214531Y-77334D01*
D02*
G37*
G36*
X205476Y-77580D02*
X204760D01*
X204099Y-77854D01*
X203592Y-78360D01*
X203318Y-79022D01*
Y-79738D01*
X203592Y-80400D01*
X204099Y-80906D01*
X204760Y-81180D01*
X205476D01*
X206138Y-80906D01*
X206644Y-80400D01*
X206918Y-79738D01*
Y-79022D01*
X206644Y-78360D01*
X206138Y-77854D01*
X205476Y-77580D01*
D02*
G37*
G36*
X543271Y-56468D02*
X542555D01*
X541894Y-56742D01*
X541387Y-57248D01*
X541113Y-57910D01*
Y-58626D01*
X541387Y-59287D01*
X541858Y-59759D01*
X541877Y-60039D01*
X541858Y-60320D01*
X541387Y-60791D01*
X541113Y-61453D01*
Y-62169D01*
X541387Y-62831D01*
X541894Y-63337D01*
X542309Y-63509D01*
Y-64050D01*
X541894Y-64222D01*
X541387Y-64728D01*
X541113Y-65390D01*
Y-66106D01*
X541387Y-66768D01*
X541859Y-67239D01*
X541877Y-67520D01*
X541859Y-67801D01*
X541387Y-68272D01*
X541113Y-68933D01*
Y-69649D01*
X541387Y-70311D01*
X541859Y-70782D01*
X541877Y-71063D01*
X541859Y-71344D01*
X541387Y-71815D01*
X541113Y-72477D01*
Y-73193D01*
X541387Y-73854D01*
X541894Y-74361D01*
X542555Y-74635D01*
X543271D01*
X543933Y-74361D01*
X544439Y-73854D01*
X544713Y-73193D01*
Y-72477D01*
X544439Y-71815D01*
X543968Y-71344D01*
X543949Y-71063D01*
X543968Y-70782D01*
X544439Y-70311D01*
X544713Y-69649D01*
Y-68933D01*
X544439Y-68272D01*
X543968Y-67801D01*
X543949Y-67520D01*
X543968Y-67239D01*
X544439Y-66768D01*
X544713Y-66106D01*
Y-65390D01*
X544439Y-64728D01*
X543933Y-64222D01*
X543518Y-64050D01*
Y-63509D01*
X543933Y-63337D01*
X544439Y-62831D01*
X544713Y-62169D01*
Y-61453D01*
X544439Y-60791D01*
X543968Y-60320D01*
X543949Y-60039D01*
X543968Y-59759D01*
X544439Y-59287D01*
X544713Y-58626D01*
Y-57910D01*
X544439Y-57248D01*
X543933Y-56742D01*
X543271Y-56468D01*
D02*
G37*
G36*
X459020Y-163554D02*
X458303D01*
X457642Y-163828D01*
X457413Y-164057D01*
X457087Y-164299D01*
X456760Y-164057D01*
X456531Y-163828D01*
X455870Y-163554D01*
X455154D01*
X454492Y-163828D01*
X454021Y-164299D01*
X453740Y-164318D01*
X453459Y-164299D01*
X452988Y-163828D01*
X452326Y-163554D01*
X451611D01*
X450949Y-163828D01*
X450478Y-164299D01*
X450197Y-164318D01*
X449916Y-164299D01*
X449445Y-163828D01*
X448783Y-163554D01*
X448067D01*
X447406Y-163828D01*
X446899Y-164335D01*
X446625Y-164996D01*
Y-165712D01*
X446899Y-166374D01*
X447406Y-166880D01*
X448067Y-167154D01*
X448783D01*
X449445Y-166880D01*
X449916Y-166409D01*
X450197Y-166390D01*
X450478Y-166409D01*
X450949Y-166880D01*
X451611Y-167154D01*
X452326D01*
X452988Y-166880D01*
X453459Y-166409D01*
X453740Y-166390D01*
X454021Y-166409D01*
X454492Y-166880D01*
X455154Y-167154D01*
X455870D01*
X456531Y-166880D01*
X456760Y-166652D01*
X457087Y-166410D01*
X457413Y-166652D01*
X457642Y-166880D01*
X458303Y-167154D01*
X459020D01*
X459681Y-166880D01*
X460187Y-166374D01*
X460461Y-165712D01*
Y-164996D01*
X460187Y-164335D01*
X459681Y-163828D01*
X459020Y-163554D01*
D02*
G37*
G36*
X443173Y-159947D02*
X442457D01*
X441795Y-160221D01*
X441289Y-160727D01*
X441015Y-161389D01*
Y-162105D01*
X441289Y-162767D01*
X441795Y-163273D01*
X442457Y-163547D01*
Y-164047D01*
X441795Y-164321D01*
X441515Y-164601D01*
X441188Y-164774D01*
X440861Y-164601D01*
X440581Y-164321D01*
X439919Y-164047D01*
X439203D01*
X438542Y-164321D01*
X438035Y-164827D01*
X437761Y-165488D01*
Y-166205D01*
X438035Y-166866D01*
X438542Y-167372D01*
X439203Y-167647D01*
X439919D01*
X440581Y-167372D01*
X440861Y-167092D01*
X441188Y-166919D01*
X441515Y-167092D01*
X441795Y-167372D01*
X442457Y-167647D01*
X443173D01*
X443835Y-167372D01*
X444341Y-166866D01*
X444615Y-166205D01*
Y-165488D01*
X444341Y-164827D01*
X443835Y-164321D01*
X443173Y-164047D01*
Y-163547D01*
X443835Y-163273D01*
X444341Y-162767D01*
X444615Y-162105D01*
Y-161389D01*
X444341Y-160727D01*
X443835Y-160221D01*
X443173Y-159947D01*
D02*
G37*
G36*
X428201Y-165166D02*
X427485D01*
X426823Y-165440D01*
X426317Y-165947D01*
X426043Y-166608D01*
Y-167324D01*
X426317Y-167986D01*
X426823Y-168492D01*
X427485Y-168766D01*
X428201D01*
X428863Y-168492D01*
X429369Y-167986D01*
X429643Y-167324D01*
Y-166608D01*
X429369Y-165947D01*
X428863Y-165440D01*
X428201Y-165166D01*
D02*
G37*
G36*
X427130Y-177728D02*
X426414D01*
X425752Y-178002D01*
X425246Y-178508D01*
X424972Y-179169D01*
Y-179886D01*
X425246Y-180547D01*
X425752Y-181053D01*
X426414Y-181328D01*
X427130D01*
X427791Y-181053D01*
X428298Y-180547D01*
X428572Y-179886D01*
Y-179169D01*
X428298Y-178508D01*
X427791Y-178002D01*
X427130Y-177728D01*
D02*
G37*
G36*
X453873Y-170151D02*
X452513D01*
X451179Y-170416D01*
X449922Y-170937D01*
X448791Y-171693D01*
X447829Y-172654D01*
X447073Y-173785D01*
X446553Y-175042D01*
X446287Y-176376D01*
Y-177737D01*
X446553Y-179071D01*
X447073Y-180327D01*
X447829Y-181458D01*
X448791Y-182420D01*
X449922Y-183176D01*
X451179Y-183697D01*
X452513Y-183962D01*
X453873D01*
X455207Y-183697D01*
X456464Y-183176D01*
X457595Y-182420D01*
X458557Y-181458D01*
X459312Y-180327D01*
X459833Y-179071D01*
X460098Y-177737D01*
Y-176376D01*
X459833Y-175042D01*
X459312Y-173785D01*
X458557Y-172654D01*
X457595Y-171693D01*
X456464Y-170937D01*
X455207Y-170416D01*
X453873Y-170151D01*
D02*
G37*
G36*
X428705Y-185995D02*
X427988D01*
X427327Y-186269D01*
X426821Y-186776D01*
X426546Y-187437D01*
Y-188153D01*
X426821Y-188815D01*
X427327Y-189321D01*
X427988Y-189595D01*
X428705D01*
X429366Y-189321D01*
X429872Y-188815D01*
X430147Y-188153D01*
Y-187437D01*
X429872Y-186776D01*
X429366Y-186269D01*
X428705Y-185995D01*
D02*
G37*
G36*
X448987Y-213889D02*
X448158D01*
X447393Y-214206D01*
X446807Y-214792D01*
X446490Y-215558D01*
Y-216387D01*
X446807Y-217152D01*
X447393Y-217738D01*
X448158Y-218055D01*
X448987D01*
X449753Y-217738D01*
X450339Y-217152D01*
X450656Y-216387D01*
Y-215558D01*
X450339Y-214792D01*
X449753Y-214206D01*
X448987Y-213889D01*
D02*
G37*
G36*
X430378Y-215211D02*
X429662D01*
X429000Y-215485D01*
X428494Y-215991D01*
X428220Y-216652D01*
Y-217369D01*
X428479Y-217995D01*
X428220Y-218621D01*
Y-219337D01*
X428479Y-219963D01*
X428220Y-220589D01*
Y-221306D01*
X428479Y-221932D01*
X428220Y-222558D01*
Y-223274D01*
X428494Y-223936D01*
X429000Y-224442D01*
X429662Y-224716D01*
X430378D01*
X431040Y-224442D01*
X431546Y-223936D01*
X431820Y-223274D01*
Y-222558D01*
X431561Y-221932D01*
X431820Y-221306D01*
Y-220589D01*
X431561Y-219963D01*
X431820Y-219337D01*
Y-218621D01*
X431561Y-217995D01*
X431820Y-217369D01*
Y-216652D01*
X431546Y-215991D01*
X431040Y-215485D01*
X430378Y-215211D01*
D02*
G37*
G36*
X452032Y-223084D02*
X451315D01*
X450654Y-223359D01*
X450148Y-223865D01*
X449873Y-224527D01*
Y-225243D01*
X450148Y-225904D01*
X450654Y-226411D01*
X451315Y-226684D01*
X452032D01*
X452693Y-226411D01*
X453199Y-225904D01*
X453474Y-225243D01*
Y-224527D01*
X453199Y-223865D01*
X452693Y-223359D01*
X452032Y-223084D01*
D02*
G37*
G36*
X446126D02*
X445410D01*
X444748Y-223359D01*
X444242Y-223865D01*
X443968Y-224527D01*
Y-225243D01*
X444242Y-225904D01*
X444748Y-226411D01*
X445410Y-226684D01*
X446126D01*
X446788Y-226411D01*
X447294Y-225904D01*
X447568Y-225243D01*
Y-224527D01*
X447294Y-223865D01*
X446788Y-223359D01*
X446126Y-223084D01*
D02*
G37*
G36*
X429886Y-229696D02*
X429170D01*
X428508Y-229970D01*
X428002Y-230476D01*
X427728Y-231138D01*
Y-231854D01*
X428002Y-232516D01*
X428508Y-233022D01*
X429170Y-233296D01*
X429886D01*
X430547Y-233022D01*
X431053Y-232516D01*
X431328Y-231854D01*
Y-231138D01*
X431053Y-230476D01*
X430547Y-229970D01*
X429886Y-229696D01*
D02*
G37*
G36*
X452032Y-232927D02*
X451315D01*
X450654Y-233201D01*
X450148Y-233707D01*
X449873Y-234369D01*
Y-235085D01*
X450148Y-235747D01*
X450654Y-236253D01*
X451315Y-236527D01*
X452032D01*
X452693Y-236253D01*
X453199Y-235747D01*
X453474Y-235085D01*
Y-234369D01*
X453199Y-233707D01*
X452693Y-233201D01*
X452032Y-232927D01*
D02*
G37*
G36*
X446126D02*
X445410D01*
X444748Y-233201D01*
X444242Y-233707D01*
X443968Y-234369D01*
Y-235085D01*
X444242Y-235747D01*
X444748Y-236253D01*
X445410Y-236527D01*
X446126D01*
X446788Y-236253D01*
X447294Y-235747D01*
X447568Y-235085D01*
Y-234369D01*
X447294Y-233707D01*
X446788Y-233201D01*
X446126Y-232927D01*
D02*
G37*
G36*
X452032Y-242770D02*
X451315D01*
X450654Y-243044D01*
X450148Y-243550D01*
X449873Y-244212D01*
Y-244928D01*
X450148Y-245589D01*
X450654Y-246096D01*
X451315Y-246370D01*
X452032D01*
X452693Y-246096D01*
X453199Y-245589D01*
X453474Y-244928D01*
Y-244212D01*
X453199Y-243550D01*
X452693Y-243044D01*
X452032Y-242770D01*
D02*
G37*
G36*
X446126D02*
X445410D01*
X444748Y-243044D01*
X444242Y-243550D01*
X443968Y-244212D01*
Y-244928D01*
X444242Y-245589D01*
X444748Y-246096D01*
X445410Y-246370D01*
X446126D01*
X446788Y-246096D01*
X447294Y-245589D01*
X447568Y-244928D01*
Y-244212D01*
X447294Y-243550D01*
X446788Y-243044D01*
X446126Y-242770D01*
D02*
G37*
G36*
X429492Y-245050D02*
X428776D01*
X428114Y-245324D01*
X427608Y-245831D01*
X427334Y-246492D01*
Y-247208D01*
X427608Y-247870D01*
X428114Y-248376D01*
X428776Y-248650D01*
X429492D01*
X430154Y-248376D01*
X430660Y-247870D01*
X430934Y-247208D01*
Y-246492D01*
X430660Y-245831D01*
X430154Y-245324D01*
X429492Y-245050D01*
D02*
G37*
G36*
X452032Y-252581D02*
X451315D01*
X450654Y-252855D01*
X450148Y-253361D01*
X449873Y-254023D01*
Y-254739D01*
X450148Y-255400D01*
X450654Y-255907D01*
X451315Y-256181D01*
X452032D01*
X452693Y-255907D01*
X453199Y-255400D01*
X453474Y-254739D01*
Y-254023D01*
X453199Y-253361D01*
X452693Y-252855D01*
X452032Y-252581D01*
D02*
G37*
G36*
X446126D02*
X445410D01*
X444748Y-252855D01*
X444242Y-253361D01*
X443968Y-254023D01*
Y-254739D01*
X444242Y-255400D01*
X444748Y-255907D01*
X445410Y-256181D01*
X446126D01*
X446788Y-255907D01*
X447294Y-255400D01*
X447568Y-254739D01*
Y-254023D01*
X447294Y-253361D01*
X446788Y-252855D01*
X446126Y-252581D01*
D02*
G37*
G36*
X432642Y-252924D02*
X431925D01*
X431264Y-253199D01*
X430758Y-253705D01*
X430483Y-254366D01*
Y-255083D01*
X430758Y-255744D01*
X431264Y-256250D01*
X431925Y-256524D01*
X432642D01*
X433303Y-256250D01*
X433809Y-255744D01*
X434084Y-255083D01*
Y-254366D01*
X433809Y-253705D01*
X433303Y-253199D01*
X432642Y-252924D01*
D02*
G37*
G36*
X452032Y-262455D02*
X451315D01*
X450654Y-262729D01*
X450148Y-263235D01*
X449873Y-263897D01*
Y-264613D01*
X450148Y-265274D01*
X450654Y-265781D01*
X451315Y-266055D01*
X452032D01*
X452693Y-265781D01*
X453199Y-265274D01*
X453474Y-264613D01*
Y-263897D01*
X453199Y-263235D01*
X452693Y-262729D01*
X452032Y-262455D01*
D02*
G37*
G36*
X446126D02*
X445410D01*
X444748Y-262729D01*
X444242Y-263235D01*
X443968Y-263897D01*
Y-264613D01*
X444242Y-265274D01*
X444748Y-265781D01*
X445410Y-266055D01*
X446126D01*
X446788Y-265781D01*
X447294Y-265274D01*
X447568Y-264613D01*
Y-263897D01*
X447294Y-263235D01*
X446788Y-262729D01*
X446126Y-262455D01*
D02*
G37*
G36*
X280740Y-272477D02*
X280024D01*
X279362Y-272751D01*
X278856Y-273257D01*
X278582Y-273919D01*
Y-274635D01*
X278856Y-275296D01*
X279362Y-275803D01*
X280024Y-276077D01*
X280740D01*
X281401Y-275803D01*
X281908Y-275296D01*
X282182Y-274635D01*
Y-273919D01*
X281908Y-273257D01*
X281401Y-272751D01*
X280740Y-272477D01*
D02*
G37*
G36*
X452032Y-273461D02*
X451315D01*
X450654Y-273735D01*
X450148Y-274241D01*
X449873Y-274903D01*
Y-275619D01*
X450148Y-276280D01*
X450654Y-276787D01*
X451315Y-277061D01*
X452032D01*
X452693Y-276787D01*
X453199Y-276280D01*
X453474Y-275619D01*
Y-274903D01*
X453199Y-274241D01*
X452693Y-273735D01*
X452032Y-273461D01*
D02*
G37*
G36*
X446126D02*
X445410D01*
X444748Y-273735D01*
X444242Y-274241D01*
X443968Y-274903D01*
Y-275619D01*
X444242Y-276280D01*
X444748Y-276787D01*
X445410Y-277061D01*
X446126D01*
X446788Y-276787D01*
X447294Y-276280D01*
X447568Y-275619D01*
Y-274903D01*
X447294Y-274241D01*
X446788Y-273735D01*
X446126Y-273461D01*
D02*
G37*
G36*
X263680Y-274266D02*
X262964D01*
X262302Y-274540D01*
X261796Y-275046D01*
X261522Y-275708D01*
Y-276424D01*
X261796Y-277085D01*
X262302Y-277592D01*
X262964Y-277866D01*
X263680D01*
X264341Y-277592D01*
X264847Y-277085D01*
X265122Y-276424D01*
Y-275708D01*
X264847Y-275046D01*
X264341Y-274540D01*
X263680Y-274266D01*
D02*
G37*
G36*
X258980D02*
X258263D01*
X257602Y-274540D01*
X257096Y-275046D01*
X256822Y-275708D01*
Y-276424D01*
X257096Y-277085D01*
X257602Y-277592D01*
X258263Y-277866D01*
X258980D01*
X259641Y-277592D01*
X260148Y-277085D01*
X260422Y-276424D01*
Y-275708D01*
X260148Y-275046D01*
X259641Y-274540D01*
X258980Y-274266D01*
D02*
G37*
G36*
X391697Y-276153D02*
X390981D01*
X390319Y-276427D01*
X389813Y-276933D01*
X389539Y-277595D01*
Y-278311D01*
X389813Y-278972D01*
X390319Y-279479D01*
X390981Y-279753D01*
X391697D01*
X392358Y-279479D01*
X392864Y-278972D01*
X393139Y-278311D01*
Y-277595D01*
X392864Y-276933D01*
X392358Y-276427D01*
X391697Y-276153D01*
D02*
G37*
G36*
X240515Y-276940D02*
X239799D01*
X239138Y-277214D01*
X238632Y-277720D01*
X238357Y-278382D01*
Y-279098D01*
X238632Y-279760D01*
X239138Y-280266D01*
X239799Y-280540D01*
X240515D01*
X241177Y-280266D01*
X241683Y-279760D01*
X241957Y-279098D01*
Y-278382D01*
X241683Y-277720D01*
X241177Y-277214D01*
X240515Y-276940D01*
D02*
G37*
G36*
X403114Y-279302D02*
X402398D01*
X401736Y-279576D01*
X401230Y-280083D01*
X400956Y-280744D01*
Y-281460D01*
X401230Y-282122D01*
X401736Y-282628D01*
X402398Y-282902D01*
X403114D01*
X403776Y-282628D01*
X404282Y-282122D01*
X404556Y-281460D01*
Y-280744D01*
X404282Y-280083D01*
X403776Y-279576D01*
X403114Y-279302D01*
D02*
G37*
G36*
X339728Y-284362D02*
X339012D01*
X338351Y-284636D01*
X337963Y-285023D01*
X337634Y-284695D01*
X336972Y-284420D01*
X336256D01*
X335595Y-284695D01*
X335088Y-285201D01*
X334814Y-285862D01*
Y-286578D01*
X335088Y-287240D01*
X335595Y-287746D01*
X336256Y-288020D01*
X336972D01*
X337634Y-287746D01*
X338021Y-287359D01*
X338351Y-287688D01*
X339012Y-287962D01*
X339728D01*
X340390Y-287688D01*
X340896Y-287181D01*
X341170Y-286520D01*
Y-285804D01*
X340896Y-285142D01*
X340390Y-284636D01*
X339728Y-284362D01*
D02*
G37*
G36*
X322208Y-281665D02*
X321492D01*
X320831Y-281939D01*
X320324Y-282445D01*
X320050Y-283106D01*
Y-283823D01*
X320324Y-284484D01*
X320831Y-284991D01*
X321492Y-285265D01*
X322208D01*
X322870Y-284991D01*
X323376Y-284484D01*
X323650Y-283823D01*
Y-283106D01*
X323376Y-282445D01*
X322870Y-281939D01*
X322208Y-281665D01*
D02*
G37*
G36*
X313744D02*
X313028D01*
X312366Y-281939D01*
X311860Y-282445D01*
X311586Y-283106D01*
Y-283823D01*
X311860Y-284484D01*
X312366Y-284991D01*
X313028Y-285265D01*
X313744D01*
X314405Y-284991D01*
X314912Y-284484D01*
X315186Y-283823D01*
Y-283106D01*
X314912Y-282445D01*
X314405Y-281939D01*
X313744Y-281665D01*
D02*
G37*
G36*
X446126Y-282140D02*
X445410D01*
X444748Y-282414D01*
X444242Y-282920D01*
X443968Y-283582D01*
Y-284298D01*
X444242Y-284959D01*
X444748Y-285466D01*
X445410Y-285740D01*
X446126D01*
X446788Y-285466D01*
X447294Y-284959D01*
X447568Y-284298D01*
Y-283582D01*
X447294Y-282920D01*
X446788Y-282414D01*
X446126Y-282140D01*
D02*
G37*
G36*
X263480Y-283966D02*
X262764D01*
X262102Y-284240D01*
X261596Y-284746D01*
X261322Y-285408D01*
Y-286124D01*
X261596Y-286785D01*
X262102Y-287292D01*
X262764Y-287566D01*
X263480D01*
X264141Y-287292D01*
X264648Y-286785D01*
X264922Y-286124D01*
Y-285408D01*
X264648Y-284746D01*
X264141Y-284240D01*
X263480Y-283966D01*
D02*
G37*
G36*
X258980D02*
X258263D01*
X257602Y-284240D01*
X257096Y-284746D01*
X256822Y-285408D01*
Y-286124D01*
X257096Y-286785D01*
X257602Y-287292D01*
X258263Y-287566D01*
X258980D01*
X259641Y-287292D01*
X260148Y-286785D01*
X260422Y-286124D01*
Y-285408D01*
X260148Y-284746D01*
X259641Y-284240D01*
X258980Y-283966D01*
D02*
G37*
G36*
X280772Y-281678D02*
X280056D01*
X279394Y-281952D01*
X278888Y-282459D01*
X278614Y-283120D01*
Y-283836D01*
X278888Y-284498D01*
X279394Y-285004D01*
X279906Y-285216D01*
Y-285740D01*
X279394Y-285952D01*
X278888Y-286459D01*
X278614Y-287120D01*
Y-287836D01*
X278888Y-288498D01*
X279394Y-289004D01*
X280056Y-289278D01*
X280772D01*
X281433Y-289004D01*
X281940Y-288498D01*
X282214Y-287836D01*
Y-287120D01*
X281940Y-286459D01*
X281433Y-285952D01*
X280921Y-285740D01*
Y-285216D01*
X281433Y-285004D01*
X281940Y-284498D01*
X282214Y-283836D01*
Y-283120D01*
X281940Y-282459D01*
X281433Y-281952D01*
X280772Y-281678D01*
D02*
G37*
G36*
X316303Y-285995D02*
X315587D01*
X314925Y-286269D01*
X314419Y-286776D01*
X314145Y-287437D01*
Y-288153D01*
X314419Y-288815D01*
X314925Y-289321D01*
X315587Y-289595D01*
X316303D01*
X316965Y-289321D01*
X317471Y-288815D01*
X317745Y-288153D01*
Y-287437D01*
X317471Y-286776D01*
X316965Y-286269D01*
X316303Y-285995D01*
D02*
G37*
G36*
X320830Y-286065D02*
X320114D01*
X319453Y-286339D01*
X318947Y-286845D01*
X318672Y-287507D01*
Y-288223D01*
X318947Y-288884D01*
X319453Y-289391D01*
X320114Y-289665D01*
X320830D01*
X321492Y-289391D01*
X321998Y-288884D01*
X322272Y-288223D01*
Y-287507D01*
X321998Y-286845D01*
X321492Y-286339D01*
X320830Y-286065D01*
D02*
G37*
G36*
X357051Y-286783D02*
X356335D01*
X355673Y-287057D01*
X355167Y-287563D01*
X354893Y-288225D01*
Y-288941D01*
X355167Y-289602D01*
X355673Y-290109D01*
X356335Y-290383D01*
X357051D01*
X357713Y-290109D01*
X358219Y-289602D01*
X358493Y-288941D01*
Y-288225D01*
X358219Y-287563D01*
X357713Y-287057D01*
X357051Y-286783D01*
D02*
G37*
G36*
X285004Y-289932D02*
X284288D01*
X283626Y-290206D01*
X283120Y-290713D01*
X282846Y-291374D01*
Y-292090D01*
X283120Y-292752D01*
X283626Y-293258D01*
X284288Y-293532D01*
X285004D01*
X285665Y-293258D01*
X286172Y-292752D01*
X286446Y-292090D01*
Y-291374D01*
X286172Y-290713D01*
X285665Y-290206D01*
X285004Y-289932D01*
D02*
G37*
G36*
X432937Y-281451D02*
X432221D01*
X431559Y-281725D01*
X431053Y-282231D01*
X430779Y-282893D01*
Y-283609D01*
X431053Y-284270D01*
X431282Y-284499D01*
X431523Y-284825D01*
X431282Y-285152D01*
X431053Y-285381D01*
X430779Y-286042D01*
Y-286758D01*
X431053Y-287420D01*
X431229Y-287596D01*
X431239Y-288294D01*
X431194Y-288338D01*
X430920Y-289000D01*
Y-289716D01*
X431194Y-290377D01*
X431431Y-290613D01*
X431309Y-290735D01*
X431035Y-291397D01*
Y-292113D01*
X431309Y-292775D01*
X431815Y-293281D01*
X432477Y-293555D01*
X433193D01*
X433854Y-293281D01*
X434361Y-292775D01*
X434635Y-292113D01*
Y-291397D01*
X434361Y-290735D01*
X434125Y-290499D01*
X434246Y-290377D01*
X434520Y-289716D01*
Y-289000D01*
X434246Y-288338D01*
X434070Y-288162D01*
X434061Y-287464D01*
X434105Y-287420D01*
X434379Y-286758D01*
Y-286042D01*
X434105Y-285381D01*
X433877Y-285152D01*
X433635Y-284825D01*
X433877Y-284499D01*
X434105Y-284270D01*
X434379Y-283609D01*
Y-282893D01*
X434105Y-282231D01*
X433599Y-281725D01*
X432937Y-281451D01*
D02*
G37*
G36*
X345519Y-291113D02*
X344803D01*
X344141Y-291387D01*
X343635Y-291894D01*
X343361Y-292555D01*
Y-293271D01*
X343635Y-293933D01*
X344141Y-294439D01*
X344803Y-294713D01*
X345519D01*
X346180Y-294439D01*
X346687Y-293933D01*
X346961Y-293271D01*
Y-292555D01*
X346687Y-291894D01*
X346180Y-291387D01*
X345519Y-291113D01*
D02*
G37*
G36*
X333823D02*
X333106D01*
X332445Y-291387D01*
X331939Y-291894D01*
X331665Y-292555D01*
Y-293271D01*
X331939Y-293933D01*
X332445Y-294439D01*
X333106Y-294713D01*
X333823D01*
X334484Y-294439D01*
X334991Y-293933D01*
X335265Y-293271D01*
Y-292555D01*
X334991Y-291894D01*
X334484Y-291387D01*
X333823Y-291113D01*
D02*
G37*
G36*
X326134Y-291901D02*
X325418D01*
X324756Y-292175D01*
X324250Y-292681D01*
X323976Y-293343D01*
Y-294059D01*
X324250Y-294720D01*
X324756Y-295227D01*
X325418Y-295501D01*
X326134D01*
X326796Y-295227D01*
X327302Y-294720D01*
X327576Y-294059D01*
Y-293343D01*
X327302Y-292681D01*
X326796Y-292175D01*
X326134Y-291901D01*
D02*
G37*
G36*
X315319D02*
X314603D01*
X313941Y-292175D01*
X313435Y-292681D01*
X313161Y-293343D01*
Y-294059D01*
X313435Y-294720D01*
X313941Y-295227D01*
X314603Y-295501D01*
X315319D01*
X315980Y-295227D01*
X316487Y-294720D01*
X316761Y-294059D01*
Y-293343D01*
X316487Y-292681D01*
X315980Y-292175D01*
X315319Y-291901D01*
D02*
G37*
G36*
X246520Y-291933D02*
X245804D01*
X245142Y-292207D01*
X244636Y-292714D01*
X244362Y-293375D01*
Y-294091D01*
X244636Y-294753D01*
X245142Y-295259D01*
X245804Y-295533D01*
X246520D01*
X247181Y-295259D01*
X247688Y-294753D01*
X247962Y-294091D01*
Y-293375D01*
X247688Y-292714D01*
X247181Y-292207D01*
X246520Y-291933D01*
D02*
G37*
G36*
X280772Y-291982D02*
X280056D01*
X279394Y-292256D01*
X278888Y-292763D01*
X278614Y-293424D01*
Y-294140D01*
X278888Y-294802D01*
X279394Y-295308D01*
X280056Y-295582D01*
X280772D01*
X281433Y-295308D01*
X281940Y-294802D01*
X282214Y-294140D01*
Y-293424D01*
X281940Y-292763D01*
X281433Y-292256D01*
X280772Y-291982D01*
D02*
G37*
G36*
X261496Y-292619D02*
X260667D01*
X259902Y-292936D01*
X259316Y-293523D01*
X258999Y-294288D01*
Y-295117D01*
X259316Y-295882D01*
X259902Y-296468D01*
X260667Y-296785D01*
X261496D01*
X262262Y-296468D01*
X262848Y-295882D01*
X263165Y-295117D01*
Y-294288D01*
X262848Y-293523D01*
X262262Y-292936D01*
X261496Y-292619D01*
D02*
G37*
G36*
X448987Y-292629D02*
X448158D01*
X447393Y-292946D01*
X446807Y-293532D01*
X446490Y-294298D01*
Y-295127D01*
X446807Y-295892D01*
X447393Y-296478D01*
X448158Y-296795D01*
X448987D01*
X449753Y-296478D01*
X450339Y-295892D01*
X450656Y-295127D01*
Y-294298D01*
X450339Y-293532D01*
X449753Y-292946D01*
X448987Y-292629D01*
D02*
G37*
G36*
X356099Y-294263D02*
X355383D01*
X354721Y-294537D01*
X354215Y-295043D01*
X353941Y-295705D01*
Y-296421D01*
X354215Y-297083D01*
X354721Y-297589D01*
X355383Y-297863D01*
X356099D01*
X356760Y-297589D01*
X357267Y-297083D01*
X357541Y-296421D01*
Y-295705D01*
X357267Y-295043D01*
X356760Y-294537D01*
X356099Y-294263D01*
D02*
G37*
G36*
X339728Y-297019D02*
X339012D01*
X338351Y-297293D01*
X337844Y-297799D01*
X337816Y-297867D01*
X337169Y-297599D01*
X336453D01*
X335791Y-297873D01*
X335285Y-298379D01*
X335011Y-299041D01*
Y-299757D01*
X335285Y-300418D01*
X335791Y-300925D01*
X336453Y-301199D01*
X337169D01*
X337831Y-300925D01*
X338337Y-300418D01*
X338365Y-300351D01*
X339012Y-300619D01*
X339728D01*
X340390Y-300345D01*
X340896Y-299838D01*
X341170Y-299177D01*
Y-298461D01*
X340896Y-297799D01*
X340390Y-297293D01*
X339728Y-297019D01*
D02*
G37*
G36*
X315691Y-297630D02*
X314975D01*
X314314Y-297904D01*
X313808Y-298411D01*
X313533Y-299072D01*
Y-299788D01*
X313808Y-300450D01*
X314314Y-300956D01*
X314975Y-301230D01*
X315691D01*
X316353Y-300956D01*
X316859Y-300450D01*
X317133Y-299788D01*
Y-299072D01*
X316859Y-298411D01*
X316353Y-297904D01*
X315691Y-297630D01*
D02*
G37*
G36*
X320830Y-297769D02*
X320114D01*
X319453Y-298043D01*
X318947Y-298550D01*
X318672Y-299211D01*
Y-299927D01*
X318947Y-300589D01*
X319453Y-301095D01*
X320114Y-301369D01*
X320830D01*
X321492Y-301095D01*
X321998Y-300589D01*
X322272Y-299927D01*
Y-299211D01*
X321998Y-298550D01*
X321492Y-298043D01*
X320830Y-297769D01*
D02*
G37*
G36*
X308626Y-298200D02*
X307910D01*
X307248Y-298474D01*
X306742Y-298980D01*
X306468Y-299642D01*
Y-300358D01*
X306742Y-301020D01*
X307248Y-301526D01*
X307910Y-301800D01*
X308626D01*
X309287Y-301526D01*
X309794Y-301020D01*
X310068Y-300358D01*
Y-299642D01*
X309794Y-298980D01*
X309287Y-298474D01*
X308626Y-298200D01*
D02*
G37*
G36*
X324542Y-300394D02*
X323826D01*
X323165Y-300668D01*
X322658Y-301174D01*
X322384Y-301835D01*
Y-302552D01*
X322658Y-303213D01*
X323165Y-303719D01*
X323826Y-303994D01*
X324542D01*
X325204Y-303719D01*
X325710Y-303213D01*
X325984Y-302552D01*
Y-301835D01*
X325710Y-301174D01*
X325204Y-300668D01*
X324542Y-300394D01*
D02*
G37*
G36*
X142484Y-346232D02*
X141768D01*
X141106Y-346505D01*
X140600Y-347012D01*
X140326Y-347674D01*
Y-348390D01*
X140600Y-349051D01*
X141106Y-349557D01*
X141768Y-349832D01*
X142484D01*
X143146Y-349557D01*
X143652Y-349051D01*
X143926Y-348390D01*
Y-347674D01*
X143652Y-347012D01*
X143146Y-346505D01*
X142484Y-346232D01*
D02*
G37*
G36*
X141946Y-350361D02*
X141229D01*
X140568Y-350635D01*
X140061Y-351142D01*
X139787Y-351803D01*
Y-352519D01*
X140061Y-353181D01*
X140568Y-353687D01*
X141229Y-353961D01*
X141946D01*
X142607Y-353687D01*
X143113Y-353181D01*
X143387Y-352519D01*
Y-351803D01*
X143113Y-351142D01*
X142607Y-350635D01*
X141946Y-350361D01*
D02*
G37*
G36*
X23586Y-145444D02*
X22870D01*
X22209Y-145718D01*
X21980Y-145947D01*
X21654Y-146188D01*
X21327Y-145947D01*
X21098Y-145718D01*
X20437Y-145444D01*
X19721D01*
X19059Y-145718D01*
X18701Y-146077D01*
X18342Y-145718D01*
X17681Y-145444D01*
X16965D01*
X16303Y-145718D01*
X15797Y-146224D01*
X15523Y-146886D01*
Y-147602D01*
X15797Y-148264D01*
X16303Y-148770D01*
X16965Y-149044D01*
X17681D01*
X18342Y-148770D01*
X18701Y-148412D01*
X19059Y-148770D01*
X19721Y-149044D01*
X20437D01*
X21098Y-148770D01*
X21327Y-148541D01*
X21654Y-148300D01*
X21980Y-148541D01*
X22209Y-148770D01*
X22870Y-149044D01*
X23586D01*
X24248Y-148770D01*
X24754Y-148264D01*
X25028Y-147602D01*
Y-146886D01*
X24754Y-146224D01*
X24248Y-145718D01*
X23586Y-145444D01*
D02*
G37*
G36*
X22799Y-165523D02*
X22083D01*
X21421Y-165797D01*
X21063Y-166155D01*
X20705Y-165797D01*
X20043Y-165523D01*
X19327D01*
X18665Y-165797D01*
X18307Y-166155D01*
X17949Y-165797D01*
X17287Y-165523D01*
X16571D01*
X15910Y-165797D01*
X15403Y-166303D01*
X15129Y-166965D01*
Y-167681D01*
X15403Y-168342D01*
X15910Y-168849D01*
X16571Y-169123D01*
X17287D01*
X17949Y-168849D01*
X18307Y-168491D01*
X18665Y-168849D01*
X19327Y-169123D01*
X20043D01*
X20705Y-168849D01*
X21063Y-168491D01*
X21421Y-168849D01*
X22083Y-169123D01*
X22799D01*
X23461Y-168849D01*
X23967Y-168342D01*
X24241Y-167681D01*
Y-166965D01*
X23967Y-166303D01*
X23461Y-165797D01*
X22799Y-165523D01*
D02*
G37*
G36*
X27523Y-177334D02*
X26807D01*
X26146Y-177608D01*
X25639Y-178114D01*
X25365Y-178776D01*
Y-179492D01*
X25639Y-180154D01*
X26146Y-180660D01*
X26807Y-180934D01*
X27523D01*
X28185Y-180660D01*
X28691Y-180154D01*
X28965Y-179492D01*
Y-178776D01*
X28691Y-178114D01*
X28185Y-177608D01*
X27523Y-177334D01*
D02*
G37*
G36*
X36185Y-183955D02*
X35469D01*
X34807Y-184229D01*
X34449Y-184588D01*
X34091Y-184229D01*
X33429Y-183955D01*
X32713D01*
X32051Y-184229D01*
X31545Y-184736D01*
X31271Y-185397D01*
Y-186113D01*
X31545Y-186775D01*
X32051Y-187281D01*
X32713Y-187555D01*
X33429D01*
X34091Y-187281D01*
X34449Y-186923D01*
X34807Y-187281D01*
X35469Y-187555D01*
X36185D01*
X36846Y-187281D01*
X37353Y-186775D01*
X37627Y-186113D01*
Y-185397D01*
X37353Y-184736D01*
X36846Y-184229D01*
X36185Y-183955D01*
D02*
G37*
G36*
X31067Y-188611D02*
X30351D01*
X29689Y-188885D01*
X29183Y-189392D01*
X28909Y-190053D01*
Y-190769D01*
X29183Y-191431D01*
X29689Y-191937D01*
X30351Y-192211D01*
X31067D01*
X31728Y-191937D01*
X32235Y-191431D01*
X32509Y-190769D01*
Y-190053D01*
X32235Y-189392D01*
X31728Y-188885D01*
X31067Y-188611D01*
D02*
G37*
G36*
X10988Y-195838D02*
X10272D01*
X9610Y-196112D01*
X9104Y-196618D01*
X8830Y-197280D01*
Y-197996D01*
X9104Y-198657D01*
X9610Y-199164D01*
X10272Y-199438D01*
X10988D01*
X11649Y-199164D01*
X12156Y-198657D01*
X12430Y-197996D01*
Y-197280D01*
X12156Y-196618D01*
X11649Y-196112D01*
X10988Y-195838D01*
D02*
G37*
G36*
X20335Y-198987D02*
X19618D01*
X18957Y-199261D01*
X18451Y-199768D01*
X18177Y-200429D01*
Y-201145D01*
X18451Y-201807D01*
X18957Y-202313D01*
X19618Y-202587D01*
X20335D01*
X20996Y-202313D01*
X21502Y-201807D01*
X21777Y-201145D01*
Y-200429D01*
X21502Y-199768D01*
X20996Y-199261D01*
X20335Y-198987D01*
D02*
G37*
G36*
Y-218672D02*
X19618D01*
X18957Y-218947D01*
X18451Y-219453D01*
X18177Y-220114D01*
Y-220830D01*
X18451Y-221492D01*
X18957Y-221998D01*
X19618Y-222272D01*
X20335D01*
X20996Y-221998D01*
X21502Y-221492D01*
X21777Y-220830D01*
Y-220114D01*
X21502Y-219453D01*
X20996Y-218947D01*
X20335Y-218672D01*
D02*
G37*
G36*
X35478Y-227137D02*
X34762D01*
X34101Y-227411D01*
X33595Y-227917D01*
X33320Y-228579D01*
Y-229295D01*
X33595Y-229957D01*
X34101Y-230463D01*
X34762Y-230737D01*
X35355D01*
X35422Y-230852D01*
X35530Y-231216D01*
X35088Y-231658D01*
X34814Y-232319D01*
Y-233035D01*
X35067Y-233647D01*
X34694Y-234020D01*
X34420Y-234681D01*
Y-235397D01*
X34531Y-235664D01*
X34020Y-235876D01*
X33513Y-236382D01*
X33239Y-237043D01*
Y-237760D01*
X33513Y-238421D01*
X34020Y-238928D01*
X34681Y-239202D01*
X35397D01*
X36059Y-238928D01*
X36565Y-238421D01*
X36839Y-237760D01*
Y-237043D01*
X36729Y-236777D01*
X37240Y-236565D01*
X37746Y-236059D01*
X38021Y-235397D01*
Y-234681D01*
X37767Y-234070D01*
X38140Y-233697D01*
X38414Y-233035D01*
Y-232319D01*
X38140Y-231658D01*
X37634Y-231151D01*
X36972Y-230877D01*
X36379D01*
X36313Y-230763D01*
X36204Y-230399D01*
X36646Y-229957D01*
X36920Y-229295D01*
Y-228579D01*
X36646Y-227917D01*
X36140Y-227411D01*
X35478Y-227137D01*
D02*
G37*
G36*
X20335Y-251153D02*
X19618D01*
X18957Y-251427D01*
X18451Y-251933D01*
X18177Y-252595D01*
Y-253311D01*
X18451Y-253972D01*
X18957Y-254479D01*
X19618Y-254753D01*
X20335D01*
X20996Y-254479D01*
X21502Y-253972D01*
X21777Y-253311D01*
Y-252595D01*
X21502Y-251933D01*
X20996Y-251427D01*
X20335Y-251153D01*
D02*
G37*
G36*
Y-270838D02*
X19618D01*
X18957Y-271112D01*
X18451Y-271618D01*
X18177Y-272280D01*
Y-272996D01*
X18451Y-273657D01*
X18957Y-274164D01*
X19618Y-274438D01*
X20335D01*
X20996Y-274164D01*
X21502Y-273657D01*
X21777Y-272996D01*
Y-272280D01*
X21502Y-271618D01*
X20996Y-271112D01*
X20335Y-270838D01*
D02*
G37*
G36*
X27425Y-280877D02*
X26709D01*
X26047Y-281151D01*
X25541Y-281658D01*
X25267Y-282319D01*
Y-283035D01*
X25541Y-283697D01*
X26047Y-284203D01*
X26709Y-284477D01*
X27425D01*
X28087Y-284203D01*
X28593Y-283697D01*
X28867Y-283035D01*
Y-282319D01*
X28593Y-281658D01*
X28087Y-281151D01*
X27425Y-280877D01*
D02*
G37*
G36*
X35397Y-284027D02*
X34681D01*
X34020Y-284301D01*
X33513Y-284807D01*
X33239Y-285469D01*
Y-286185D01*
X33513Y-286846D01*
X34020Y-287353D01*
X34681Y-287627D01*
X35397D01*
X36059Y-287353D01*
X36565Y-286846D01*
X36839Y-286185D01*
Y-285469D01*
X36565Y-284807D01*
X36059Y-284301D01*
X35397Y-284027D01*
D02*
G37*
G36*
Y-288161D02*
X34681D01*
X34020Y-288435D01*
X33513Y-288941D01*
X33239Y-289603D01*
Y-290319D01*
X33513Y-290980D01*
X34020Y-291487D01*
X34681Y-291761D01*
X35397D01*
X36059Y-291487D01*
X36565Y-290980D01*
X36839Y-290319D01*
Y-289603D01*
X36565Y-288941D01*
X36059Y-288435D01*
X35397Y-288161D01*
D02*
G37*
G36*
X10988Y-290326D02*
X10272D01*
X9610Y-290600D01*
X9104Y-291106D01*
X8830Y-291768D01*
Y-292484D01*
X9104Y-293146D01*
X9610Y-293652D01*
X10272Y-293926D01*
X10988D01*
X11649Y-293652D01*
X12156Y-293146D01*
X12430Y-292484D01*
Y-291768D01*
X12156Y-291106D01*
X11649Y-290600D01*
X10988Y-290326D01*
D02*
G37*
G36*
X27425Y-296927D02*
X26709D01*
X26047Y-297201D01*
X25541Y-297707D01*
X25267Y-298369D01*
Y-299085D01*
X25541Y-299746D01*
X26047Y-300253D01*
X26709Y-300527D01*
X27425D01*
X28087Y-300253D01*
X28593Y-299746D01*
X28867Y-299085D01*
Y-298369D01*
X28593Y-297707D01*
X28087Y-297201D01*
X27425Y-296927D01*
D02*
G37*
G36*
X20335Y-305287D02*
X19618D01*
X18957Y-305561D01*
X18451Y-306067D01*
X18177Y-306729D01*
Y-307445D01*
X18451Y-308106D01*
X18957Y-308613D01*
X19618Y-308887D01*
X20335D01*
X20996Y-308613D01*
X21502Y-308106D01*
X21777Y-307445D01*
Y-306729D01*
X21502Y-306067D01*
X20996Y-305561D01*
X20335Y-305287D01*
D02*
G37*
G36*
Y-324972D02*
X19618D01*
X18957Y-325246D01*
X18451Y-325752D01*
X18177Y-326414D01*
Y-327130D01*
X18451Y-327791D01*
X18957Y-328298D01*
X19618Y-328572D01*
X20335D01*
X20996Y-328298D01*
X21502Y-327791D01*
X21777Y-327130D01*
Y-326414D01*
X21502Y-325752D01*
X20996Y-325246D01*
X20335Y-324972D01*
D02*
G37*
G36*
X22405Y-333633D02*
X21689D01*
X21028Y-333907D01*
X20521Y-334414D01*
X20247Y-335075D01*
Y-335791D01*
X20521Y-336453D01*
X21028Y-336959D01*
X21689Y-337233D01*
X22405D01*
X23067Y-336959D01*
X23573Y-336453D01*
X23847Y-335791D01*
Y-335075D01*
X23573Y-334414D01*
X23067Y-333907D01*
X22405Y-333633D01*
D02*
G37*
G36*
X27917Y-335602D02*
X27201D01*
X26539Y-335876D01*
X26033Y-336382D01*
X25759Y-337043D01*
Y-337760D01*
X26033Y-338421D01*
X26539Y-338928D01*
X27201Y-339202D01*
X27917D01*
X28579Y-338928D01*
X29085Y-338421D01*
X29359Y-337760D01*
Y-337043D01*
X29085Y-336382D01*
X28579Y-335876D01*
X27917Y-335602D01*
D02*
G37*
G36*
X29901Y-343414D02*
X29185D01*
X28523Y-343688D01*
X28017Y-344195D01*
X27743Y-344856D01*
Y-345572D01*
X28017Y-346234D01*
X28523Y-346740D01*
X29185Y-347014D01*
X29901D01*
X30563Y-346740D01*
X31069Y-346234D01*
X31343Y-345572D01*
Y-344856D01*
X31069Y-344195D01*
X30563Y-343688D01*
X29901Y-343414D01*
D02*
G37*
G36*
X27130Y-347019D02*
X26414D01*
X25752Y-347293D01*
X25246Y-347799D01*
X24972Y-348461D01*
Y-349177D01*
X25246Y-349838D01*
X25752Y-350345D01*
X26414Y-350619D01*
X27130D01*
X27791Y-350345D01*
X28298Y-349838D01*
X28572Y-349177D01*
Y-348461D01*
X28298Y-347799D01*
X27791Y-347293D01*
X27130Y-347019D01*
D02*
G37*
G36*
X481854Y-195444D02*
X481138D01*
X480476Y-195718D01*
X479970Y-196224D01*
X479696Y-196886D01*
Y-197602D01*
X479970Y-198264D01*
X480476Y-198770D01*
X481138Y-199044D01*
X481854D01*
X482516Y-198770D01*
X483022Y-198264D01*
X483296Y-197602D01*
Y-196886D01*
X483022Y-196224D01*
X482516Y-195718D01*
X481854Y-195444D01*
D02*
G37*
G36*
X522012Y-197019D02*
X521295D01*
X520634Y-197293D01*
X520128Y-197799D01*
X519853Y-198461D01*
Y-198473D01*
X519725Y-198666D01*
X519616Y-199213D01*
X519725Y-199759D01*
X520034Y-200222D01*
X520497Y-200531D01*
X521043Y-200640D01*
X521248Y-200599D01*
X521295Y-200619D01*
X522012D01*
X522673Y-200345D01*
X523179Y-199838D01*
X523454Y-199177D01*
Y-198461D01*
X523179Y-197799D01*
X522673Y-197293D01*
X522012Y-197019D01*
D02*
G37*
G36*
X513744Y-197413D02*
X513028D01*
X512366Y-197687D01*
X511860Y-198193D01*
X511586Y-198855D01*
Y-199571D01*
X511860Y-200232D01*
X512366Y-200739D01*
X513028Y-201013D01*
X513744D01*
X514405Y-200739D01*
X514912Y-200232D01*
X515186Y-199571D01*
Y-198855D01*
X514912Y-198193D01*
X514405Y-197687D01*
X513744Y-197413D01*
D02*
G37*
G36*
X488547Y-214735D02*
X487831D01*
X487169Y-215009D01*
X486663Y-215516D01*
X486389Y-216177D01*
Y-216894D01*
X486663Y-217555D01*
X487169Y-218061D01*
X487831Y-218335D01*
X488547D01*
X489209Y-218061D01*
X489715Y-217555D01*
X489989Y-216894D01*
Y-216177D01*
X489715Y-215516D01*
X489209Y-215009D01*
X488547Y-214735D01*
D02*
G37*
G36*
X501329Y-218095D02*
X500613D01*
X499951Y-218370D01*
X499445Y-218876D01*
X499171Y-219537D01*
Y-220253D01*
X499445Y-220915D01*
X499951Y-221422D01*
X500613Y-221695D01*
X501329D01*
X501990Y-221422D01*
X502497Y-220915D01*
X502771Y-220253D01*
Y-219537D01*
X502497Y-218876D01*
X501990Y-218370D01*
X501329Y-218095D01*
D02*
G37*
G36*
X571618Y-254991D02*
X570902D01*
X570240Y-255265D01*
X570079Y-255427D01*
X569917Y-255265D01*
X569256Y-254991D01*
X568540D01*
X567878Y-255265D01*
X567372Y-255772D01*
X567098Y-256433D01*
Y-257149D01*
X567372Y-257811D01*
X567878Y-258317D01*
X568540Y-258591D01*
X569256D01*
X569917Y-258317D01*
X570079Y-258156D01*
X570240Y-258317D01*
X570902Y-258591D01*
X571618D01*
X572280Y-258317D01*
X572786Y-257811D01*
X573060Y-257149D01*
Y-256433D01*
X572786Y-255772D01*
X572280Y-255265D01*
X571618Y-254991D01*
D02*
G37*
G36*
X564531Y-254105D02*
X563815D01*
X563154Y-254380D01*
X562647Y-254886D01*
X562373Y-255547D01*
Y-256263D01*
X562647Y-256925D01*
X563154Y-257432D01*
X563815Y-257705D01*
X564531D01*
X565193Y-257432D01*
X565699Y-256925D01*
X565973Y-256263D01*
Y-255547D01*
X565699Y-254886D01*
X565193Y-254380D01*
X564531Y-254105D01*
D02*
G37*
G36*
X555082Y-270641D02*
X554366D01*
X553705Y-270915D01*
X553198Y-271421D01*
X552924Y-272083D01*
Y-272799D01*
X553198Y-273461D01*
X553705Y-273967D01*
X554366Y-274241D01*
X555082D01*
X555744Y-273967D01*
X556250Y-273461D01*
X556524Y-272799D01*
Y-272083D01*
X556250Y-271421D01*
X555744Y-270915D01*
X555082Y-270641D01*
D02*
G37*
G36*
X555818Y-282601D02*
X555102D01*
X554440Y-282875D01*
X553934Y-283381D01*
X553660Y-284043D01*
Y-284759D01*
X553934Y-285420D01*
X554440Y-285927D01*
X555102Y-286201D01*
X555818D01*
X556479Y-285927D01*
X556986Y-285420D01*
X557260Y-284759D01*
Y-284043D01*
X556986Y-283381D01*
X556479Y-282875D01*
X555818Y-282601D01*
D02*
G37*
G36*
X541451Y-282826D02*
X540735D01*
X540074Y-283101D01*
X539567Y-283607D01*
X539293Y-284268D01*
Y-284984D01*
X539567Y-285646D01*
X540074Y-286152D01*
X540735Y-286426D01*
X541451D01*
X542113Y-286152D01*
X542619Y-285646D01*
X542893Y-284984D01*
Y-284268D01*
X542619Y-283607D01*
X542113Y-283101D01*
X541451Y-282826D01*
D02*
G37*
G36*
X523193Y-295936D02*
X522477D01*
X521815Y-296210D01*
X521309Y-296717D01*
X521035Y-297378D01*
Y-298094D01*
X521309Y-298756D01*
X521815Y-299262D01*
X522477Y-299536D01*
X523193D01*
X523854Y-299262D01*
X524361Y-298756D01*
X524635Y-298094D01*
Y-297378D01*
X524361Y-296717D01*
X523854Y-296210D01*
X523193Y-295936D01*
D02*
G37*
G36*
X517287Y-296330D02*
X516571D01*
X515909Y-296604D01*
X515403Y-297110D01*
X515129Y-297772D01*
Y-298488D01*
X515403Y-299149D01*
X515909Y-299656D01*
X516571Y-299930D01*
X517287D01*
X517949Y-299656D01*
X518455Y-299149D01*
X518729Y-298488D01*
Y-297772D01*
X518455Y-297110D01*
X517949Y-296604D01*
X517287Y-296330D01*
D02*
G37*
G36*
X513764Y-301102D02*
X513048D01*
X512386Y-301376D01*
X511880Y-301883D01*
X511606Y-302544D01*
Y-303260D01*
X511880Y-303922D01*
X512386Y-304428D01*
X513048Y-304702D01*
X513764D01*
X514426Y-304428D01*
X514932Y-303922D01*
X515206Y-303260D01*
Y-302544D01*
X514932Y-301883D01*
X514426Y-301376D01*
X513764Y-301102D01*
D02*
G37*
G36*
X553114Y-334027D02*
X552398D01*
X551736Y-334301D01*
X551230Y-334807D01*
X550956Y-335469D01*
Y-336185D01*
X551230Y-336846D01*
X551736Y-337353D01*
X552398Y-337627D01*
X553114D01*
X553776Y-337353D01*
X554282Y-336846D01*
X554556Y-336185D01*
Y-335469D01*
X554282Y-334807D01*
X553776Y-334301D01*
X553114Y-334027D01*
D02*
G37*
G36*
X545240Y-334420D02*
X544524D01*
X543862Y-334695D01*
X543356Y-335201D01*
X543082Y-335862D01*
Y-336578D01*
X543356Y-337240D01*
X543862Y-337746D01*
X544524Y-338020D01*
X545240D01*
X545901Y-337746D01*
X546408Y-337240D01*
X546682Y-336578D01*
Y-335862D01*
X546408Y-335201D01*
X545901Y-334695D01*
X545240Y-334420D01*
D02*
G37*
G36*
X522012D02*
X521295D01*
X520634Y-334695D01*
X520128Y-335201D01*
X519853Y-335862D01*
Y-336578D01*
X520128Y-337240D01*
X520634Y-337746D01*
X521295Y-338020D01*
X522012D01*
X522673Y-337746D01*
X523179Y-337240D01*
X523454Y-336578D01*
Y-335862D01*
X523179Y-335201D01*
X522673Y-334695D01*
X522012Y-334420D01*
D02*
G37*
G36*
X513744D02*
X513028D01*
X512366Y-334695D01*
X511860Y-335201D01*
X511586Y-335862D01*
Y-336578D01*
X511860Y-337240D01*
X512366Y-337746D01*
X513028Y-338020D01*
X513744D01*
X514405Y-337746D01*
X514912Y-337240D01*
X515186Y-336578D01*
Y-335862D01*
X514912Y-335201D01*
X514405Y-334695D01*
X513744Y-334420D01*
D02*
G37*
G36*
X555870Y-338357D02*
X555154D01*
X554492Y-338632D01*
X553986Y-339138D01*
X553712Y-339799D01*
Y-340515D01*
X553986Y-341177D01*
X554492Y-341683D01*
X555154Y-341957D01*
X555870D01*
X556531Y-341683D01*
X557038Y-341177D01*
X557312Y-340515D01*
Y-339799D01*
X557038Y-339138D01*
X556531Y-338632D01*
X555870Y-338357D01*
D02*
G37*
%LPD*%
D11*
X198819Y-81890D02*
X202362D01*
X192520Y-88189D02*
X198819Y-81890D01*
X189764Y-88189D02*
X192520D01*
X209449Y-100394D02*
Y-82284D01*
X203918Y-105925D02*
X209449Y-100394D01*
X199193Y-105925D02*
X203918D01*
D16*
X356013Y-355906D02*
G03*
X363862Y-352654I0J11100D01*
G01*
X367008Y-346573D02*
G03*
X366594Y-347573I999J-999D01*
G01*
X238607Y-375270D02*
G03*
X244966Y-375972I3616J3608D01*
G01*
D02*
G03*
X246613Y-372971I-1910J3001D01*
G01*
X329528Y-352756D02*
G03*
X337131Y-355906I7604J7604D01*
G01*
X329528Y-352756D02*
G03*
X326676Y-351575I-2851J-2851D01*
G01*
X253564Y-353522D02*
G03*
X253543Y-353543I4732J-4773D01*
G01*
X258296Y-351575D02*
G03*
X258267Y-351575I0J-6721D01*
G01*
X246874Y-360212D02*
G03*
X246613Y-360844I633J-631D01*
G01*
X246875Y-360212D02*
G03*
X246874Y-360212I632J-632D01*
G01*
X356013Y-354805D02*
G03*
X363084Y-351877I0J10000D01*
G01*
X365494Y-347573D02*
G03*
X365080Y-346573I-1413J0D01*
G01*
X241929Y-374655D02*
G03*
X244862Y-374595I1438J1455D01*
G01*
X330305Y-351978D02*
G03*
X337131Y-354805I6826J6826D01*
G01*
X330305Y-351978D02*
G03*
X326676Y-350475I-3629J-3629D01*
G01*
X259654D02*
G03*
X251805Y-353726I0J-11100D01*
G01*
X246109Y-359422D02*
G03*
X245513Y-360861I1440J-1440D01*
G01*
X365738Y-350778D02*
G03*
X366594Y-348713I-2065J2065D01*
G01*
X244763Y-363361D02*
G03*
X245513Y-362611I0J750D01*
G01*
X244561Y-363361D02*
G03*
X244561Y-364861I0J-750D01*
G01*
X244863Y-366361D02*
G03*
X244863Y-364861I0J750D01*
G01*
X244678Y-366361D02*
G03*
X244678Y-367861I0J-750D01*
G01*
X244863Y-369361D02*
G03*
X244863Y-367861I0J750D01*
G01*
X244763Y-369361D02*
G03*
X244763Y-370861I0J-750D01*
G01*
X245513Y-371611D02*
G03*
X244763Y-370861I-750J0D01*
G01*
X244994Y-374439D02*
G03*
X245061Y-374345I-2061J1552D01*
G01*
X244862Y-374595D02*
G03*
X244992Y-374441I-1496J1395D01*
G01*
X364617Y-350344D02*
G03*
X365494Y-348227I-2117J2117D01*
G01*
X253613Y-353480D02*
G03*
X253564Y-353522I301J-399D01*
G01*
X258202Y-351580D02*
G03*
X253613Y-353480I1452J-9995D01*
G01*
X258267Y-351575D02*
G03*
X258202Y-351580I5J-500D01*
G01*
X331381Y-342404D02*
G03*
X330709Y-342126I-672J-672D01*
G01*
X266992D02*
G03*
X264164Y-343298I0J-4000D01*
G01*
X261289Y-344488D02*
G03*
X264164Y-343298I0J4065D01*
G01*
X353622Y-346573D02*
G03*
X353208Y-347573I999J-999D01*
G01*
X352638Y-349169D02*
G03*
X353208Y-347793I-1376J1376D01*
G01*
X346058Y-351969D02*
G03*
X352522Y-349286I-13J9160D01*
G01*
X346045Y-351969D02*
G03*
X346058Y-351969I0J9160D01*
G01*
X338420Y-349444D02*
G03*
X338426Y-349450I6095J6095D01*
G01*
X343491Y-351907D02*
G03*
X344515Y-351969I1024J8558D01*
G01*
X338426Y-349450D02*
G03*
X343491Y-351907I6089J6100D01*
G01*
X248127Y-344488D02*
G03*
X248091Y-344488I0J-4033D01*
G01*
D02*
G03*
X248014Y-344495I7J-500D01*
G01*
Y-344495D02*
G03*
X245363Y-345593I1199J-6646D01*
G01*
D02*
G03*
X245300Y-345645I287J-410D01*
G01*
D02*
G03*
X245276Y-345669I2827J-2876D01*
G01*
X235783Y-355162D02*
G03*
X233227Y-361332I6170J-6170D01*
G01*
X207768Y-374868D02*
G03*
X207415Y-374722I-354J-354D01*
G01*
X206496Y-374655D02*
G03*
X206656Y-374722I160J160D01*
G01*
X229980Y-376349D02*
G03*
X233227Y-368509I-7840J7840D01*
G01*
X207915Y-375449D02*
G03*
X208222Y-376192I1050J0D01*
G01*
X225005Y-380873D02*
G03*
X225774Y-380554I0J1088D01*
G01*
X210420Y-378390D02*
G03*
X216416Y-380873I5996J5996D01*
G01*
X207915Y-375221D02*
G03*
X207768Y-374868I-500J0D01*
G01*
X332158Y-341626D02*
G03*
X330709Y-341026I-1450J-1450D01*
G01*
X332159Y-341627D02*
X332158Y-341626D01*
X266992Y-341026D02*
G03*
X263386Y-342520I0J-5100D01*
G01*
X261289Y-343388D02*
G03*
X263386Y-342520I0J2965D01*
G01*
X249213Y-343388D02*
G03*
X243730Y-345659I0J-7753D01*
G01*
X352108Y-347573D02*
G03*
X351694Y-346573I-1413J0D01*
G01*
X351744Y-348508D02*
G03*
X352108Y-347629I-879J879D01*
G01*
X346045Y-350869D02*
G03*
X351744Y-348508I0J8060D01*
G01*
X338876Y-348344D02*
G03*
X344971Y-350869I6095J6095D01*
G01*
X235005Y-354384D02*
G03*
X232127Y-361332I6948J-6948D01*
G01*
X229198Y-375575D02*
G03*
X232127Y-368504I-7071J7071D01*
G01*
X216706Y-377977D02*
G03*
X215206Y-377977I-750J0D01*
G01*
X211187Y-377601D02*
G03*
X212402Y-378583I5244J5244D01*
G01*
X210273Y-374722D02*
G03*
X210433Y-374655I0J227D01*
G01*
X209515Y-374722D02*
G03*
X209161Y-374868I0J-500D01*
G01*
X209161Y-374868D02*
G03*
X209015Y-375221I353J-353D01*
G01*
X209015D02*
G03*
X209161Y-375575I500J0D01*
G01*
X216706Y-379023D02*
G03*
X217456Y-379773I750J0D01*
G01*
X214258Y-379178D02*
G03*
X215206Y-378455I198J723D01*
G01*
X212402Y-378583D02*
G03*
X212652Y-378738I4030J6227D01*
G01*
X216056Y-374106D02*
G03*
X217251Y-374601I1194J1194D01*
G01*
X332850Y-328126D02*
G03*
X325779Y-325197I-7071J-7071D01*
G01*
X250671Y-325571D02*
G03*
X250670Y-325572I904J-905D01*
G01*
X362408Y-326856D02*
G03*
X361580Y-328855I1999J-1999D01*
G01*
X217251Y-374601D02*
G03*
X218420Y-374116I0J1654D01*
G01*
X216986Y-362377D02*
G03*
X214518Y-366447I7071J-7071D01*
G01*
X359448Y-335911D02*
G03*
X360226Y-335589I0J1100D01*
G01*
X243241Y-336122D02*
G03*
X245448Y-330794I-5328J5328D01*
G01*
X214518Y-366447D02*
G03*
X214057Y-369448I9539J-3002D01*
G01*
X360479Y-335336D02*
G03*
X361580Y-332677I-2659J2659D01*
G01*
X337380Y-332655D02*
G03*
X345229Y-335906I7849J7849D01*
G01*
X214057Y-371682D02*
G03*
X214357Y-372406I1024J0D01*
G01*
X251575Y-325197D02*
G03*
X250671Y-325571I0J-1279D01*
G01*
X221108Y-376185D02*
G03*
X222638Y-374655I0J1530D01*
G01*
X338157Y-331877D02*
G03*
X345229Y-334806I7071J7071D01*
G01*
X212957Y-371682D02*
G03*
X213579Y-373184I2124J0D01*
G01*
X242463Y-335344D02*
G03*
X244348Y-330794I-4551J4551D01*
G01*
X359701Y-334558D02*
G03*
X360480Y-332677I-1881J1881D01*
G01*
X251575Y-324097D02*
G03*
X249892Y-324794I0J-2379D01*
G01*
X360480Y-328855D02*
G03*
X359652Y-326856I-2827J0D01*
G01*
X217904Y-376102D02*
G03*
X218177Y-376185I276J417D01*
G01*
X333628Y-327348D02*
G03*
X325779Y-324097I-7849J-7849D01*
G01*
X215717Y-375322D02*
G03*
X217308Y-375984I1590J1576D01*
G01*
X216204Y-361603D02*
G03*
X212957Y-369443I7840J-7840D01*
G01*
X217904Y-376102D02*
G03*
X217520Y-375984I-384J-568D01*
G01*
X244670Y-330016D02*
G03*
X244348Y-330794I779J-777D01*
G01*
X267592Y-359055D02*
G03*
X260521Y-361984I0J-10000D01*
G01*
X380807Y-346144D02*
G03*
X379783Y-348619I2474J-2474D01*
G01*
X259655Y-367004D02*
G03*
X259802Y-366651I-353J354D01*
G01*
X379124Y-350384D02*
G03*
X379783Y-348795I-1589J1589D01*
G01*
X365856Y-359055D02*
G03*
X373704Y-355804I-0J11100D01*
G01*
X259729Y-364111D02*
G03*
X259802Y-364289I251J0D01*
G01*
X259655Y-367004D02*
G03*
X259653Y-367007I351J-356D01*
G01*
X258947Y-362003D02*
G03*
X258946Y-362003I769J-769D01*
G01*
X378683Y-348220D02*
G03*
X377940Y-346426I-2536J0D01*
G01*
X256258Y-374866D02*
G03*
X255841Y-375038I0J-590D01*
G01*
X255508Y-375906D02*
G03*
X255668Y-375539I-340J367D01*
G01*
X377940Y-350013D02*
G03*
X378683Y-348220I-1793J1793D01*
G01*
X255841Y-375039D02*
G03*
X255668Y-375456I417J-417D01*
G01*
X251794Y-374454D02*
G03*
X252426Y-375861I2176J133D01*
G01*
X365856Y-357955D02*
G03*
X372927Y-355026I0J10000D01*
G01*
X252429Y-375863D02*
G03*
X255508Y-375906I1562J1586D01*
G01*
X258555Y-366297D02*
G03*
X258629Y-366120I-178J178D01*
G01*
X256382Y-374866D02*
G03*
X256890Y-374655I0J719D01*
G01*
X267307Y-357955D02*
G03*
X259945Y-361005I0J-10411D01*
G01*
X252650Y-372202D02*
G03*
X251793Y-374451I2117J-2094D01*
G01*
X258946Y-362003D02*
G03*
X258629Y-362771I769J-768D01*
G01*
X382668Y-321663D02*
G03*
X379989Y-320553I-2679J-2679D01*
G01*
X374409D02*
G03*
X373632Y-320876I0J-1100D01*
G01*
X272159Y-366037D02*
G03*
X272019Y-366318I355J-352D01*
G01*
X373632Y-320876D02*
G03*
X372186Y-324364I3489J-3489D01*
G01*
X388502Y-332095D02*
G03*
X385250Y-324246I-11100J0D01*
G01*
X385252Y-352830D02*
G03*
X388502Y-344983I-7851J7847D01*
G01*
X371359Y-328019D02*
G03*
X372186Y-326020I-1999J1999D01*
G01*
X273425Y-374655D02*
G03*
X273296Y-374344I-440J0D01*
G01*
X385250Y-352832D02*
G03*
X385252Y-352830I-7849J7849D01*
G01*
X370886Y-362598D02*
G03*
X378735Y-359347I0J11100D01*
G01*
X278777Y-362598D02*
G03*
X273590Y-364747I0J-7335D01*
G01*
X272014Y-371248D02*
G03*
X273296Y-374344I4379J0D01*
G01*
X387502Y-332095D02*
G03*
X386232Y-327192I-10100J0D01*
G01*
X273575Y-363400D02*
G03*
X273679Y-363339I-198J459D01*
G01*
X269813Y-374162D02*
G03*
X270914Y-371505I-2657J2657D01*
G01*
X386232Y-327192D02*
G03*
X386216Y-327166I-435J-246D01*
G01*
X385475Y-351051D02*
G03*
X387502Y-344983I-8074J6069D01*
G01*
X269502Y-374291D02*
G03*
X269813Y-374162I0J440D01*
G01*
X381890Y-322441D02*
G03*
X379989Y-321654I-1901J-1901D01*
G01*
X386216Y-327166D02*
G03*
X386189Y-327124I-11306J-7421D01*
G01*
X370886Y-361498D02*
G03*
X377957Y-358570I0J10000D01*
G01*
X273575Y-363400D02*
G03*
X273498Y-363435I723J-1713D01*
G01*
X365198Y-361498D02*
G03*
X364957Y-361598I0J-341D01*
G01*
X278269Y-361614D02*
G03*
X273679Y-363339I507J-8319D01*
G01*
X386189Y-327124D02*
G03*
X384473Y-325024I-11279J-7462D01*
G01*
X278269Y-361614D02*
G03*
X278362Y-361598I-35J499D01*
G01*
X374409Y-321654D02*
G03*
X373287Y-324364I2711J-2711D01*
G01*
X273498Y-363435D02*
G03*
X272983Y-363798I800J-1678D01*
G01*
X373287Y-326020D02*
G03*
X374114Y-328019I2827J-0D01*
G01*
X227373Y-351990D02*
G03*
X227373Y-353050I530J-530D01*
G01*
X227473Y-354211D02*
G03*
X227473Y-353150I-530J530D01*
G01*
X226412Y-354211D02*
G03*
X227473Y-354211I530J530D01*
G01*
X226281Y-354080D02*
G03*
X225221Y-354080I-530J-530D01*
G01*
D02*
G03*
X225221Y-355141I530J-530D01*
G01*
X225352Y-356332D02*
G03*
X225352Y-355271I-530J530D01*
G01*
X224291Y-356332D02*
G03*
X225352Y-356332I530J530D01*
G01*
X224160Y-356201D02*
G03*
X223099Y-356201I-530J-530D01*
G01*
D02*
G03*
X223099Y-357262I530J-530D01*
G01*
X223230Y-358453D02*
G03*
X223230Y-357393I-530J530D01*
G01*
X222170Y-358453D02*
G03*
X223230Y-358453I530J530D01*
G01*
X222070Y-358354D02*
G03*
X221009Y-358354I-530J-530D01*
G01*
X285027Y-360848D02*
G03*
X285777Y-361598I750J0D01*
G01*
X285027Y-360848D02*
G03*
X283527Y-360848I-750J0D01*
G01*
X282027Y-360848D02*
G03*
X283527Y-360848I750J0D01*
G01*
X282027Y-360848D02*
G03*
X280527Y-360848I-750J0D01*
G01*
X279777Y-361598D02*
G03*
X280527Y-360848I0J750D01*
G01*
X256207Y-371514D02*
G03*
X255146Y-371514I-530J-530D01*
G01*
X256609Y-371916D02*
G03*
X257669Y-371916I530J530D01*
G01*
D02*
G03*
X257669Y-370855I-530J530D01*
G01*
X257070Y-369196D02*
G03*
X257070Y-370256I530J-530D01*
G01*
X258131Y-369196D02*
G03*
X257070Y-369196I-530J-530D01*
G01*
X258730Y-369795D02*
G03*
X259791Y-369795I530J530D01*
G01*
D02*
G03*
X259791Y-368734I-530J530D01*
G01*
X259389Y-367271D02*
G03*
X259389Y-368332I530J-530D01*
G01*
X337131Y-355906D02*
X356013D01*
X366594Y-348713D02*
Y-347573D01*
X246613Y-372967D02*
Y-360844D01*
X238607Y-375270D02*
X238607Y-375270D01*
X246613Y-372971D02*
X246613Y-372967D01*
X258296Y-351575D02*
X326676D01*
X246875Y-360212D02*
X253543Y-353543D01*
X246874Y-360212D02*
X246875Y-360212D01*
X363084Y-351877D02*
X364617Y-350344D01*
X365494Y-348227D02*
Y-347573D01*
X241929Y-374655D02*
X241929Y-374655D01*
X337131Y-354805D02*
X356013D01*
X259654Y-350475D02*
X326676D01*
X246109Y-359422D02*
X251805Y-353726D01*
X363862Y-352654D02*
X365738Y-350778D01*
X367008Y-346573D02*
X367422Y-346159D01*
Y-346144D01*
X237992Y-374655D02*
X238607Y-375270D01*
X245513Y-362611D02*
Y-360861D01*
X244561Y-363361D02*
X244763D01*
X244561Y-364861D02*
X244863D01*
X244678Y-366361D02*
X244863D01*
X244678Y-367861D02*
X244863D01*
X244763Y-369361D02*
X244863D01*
X244763Y-370861D02*
X244763D01*
X245513Y-372887D02*
Y-371611D01*
X245061Y-374345D02*
X245513Y-372887D01*
X244992Y-374441D02*
X244994Y-374439D01*
X364666Y-346159D02*
Y-346144D01*
Y-346159D02*
X365080Y-346573D01*
X354036Y-346159D02*
Y-346144D01*
X353622Y-346573D02*
X354036Y-346159D01*
X266992Y-342126D02*
X330709D01*
X248127Y-344488D02*
X261289D01*
X353208Y-347793D02*
Y-347573D01*
X352522Y-349286D02*
X352638Y-349169D01*
X344515Y-351969D02*
X346045D01*
X331381Y-342404D02*
X338420Y-349444D01*
X238971Y-351974D02*
X245276Y-345669D01*
X235783Y-355162D02*
X238971Y-351974D01*
X233227Y-368509D02*
Y-361332D01*
X206656Y-374722D02*
X207415D01*
X225774Y-380554D02*
X229980Y-376349D01*
X208222Y-376192D02*
X210420Y-378390D01*
X216416Y-380873D02*
X225005D01*
X207915Y-375449D02*
Y-375221D01*
X332158Y-341626D02*
X332159Y-341627D01*
X351280Y-346159D02*
Y-346144D01*
X266992Y-341026D02*
X330709D01*
X249213Y-343388D02*
X261289D01*
X352108Y-347629D02*
Y-347573D01*
X351280Y-346159D02*
X351694Y-346573D01*
X344971Y-350869D02*
X346045D01*
X337489Y-346957D02*
X338876Y-348344D01*
X332159Y-341627D02*
X337489Y-346957D01*
X238473Y-350916D02*
X243730Y-345659D01*
X235005Y-354384D02*
X238473Y-350916D01*
X232127Y-368504D02*
Y-361332D01*
X209161Y-375575D02*
X211187Y-377601D01*
X215206Y-378455D02*
Y-377977D01*
X209515Y-374722D02*
X210273D01*
X209015Y-375221D02*
X209015D01*
X225000Y-379773D02*
X229198Y-375575D01*
X216706Y-379023D02*
Y-377977D01*
X219207Y-379773D02*
X225000Y-379773D01*
X219207Y-379773D02*
X219207D01*
X217456D02*
X219207D01*
X212402Y-378583D02*
X212402Y-378583D01*
X212652Y-378738D02*
X214258Y-379178D01*
X214258Y-379178D02*
X214258Y-379178D01*
X250670Y-325572D02*
X250671Y-325571D01*
X218420Y-374116D02*
X218444Y-374109D01*
X214357Y-372406D02*
X216056Y-374106D01*
X362408Y-326856D02*
Y-326841D01*
X361580Y-332677D02*
Y-328855D01*
X352431Y-335906D02*
X352435Y-335911D01*
X359448D01*
X245448Y-330794D02*
X250670Y-325572D01*
X218444Y-374109D02*
X218445Y-374108D01*
X360226Y-335589D02*
X360479Y-335336D01*
X232522Y-346841D02*
X243241Y-336122D01*
X251575Y-325197D02*
X325779D01*
X214057Y-371682D02*
Y-369448D01*
X216986Y-362377D02*
X219772Y-359591D01*
X345229Y-335906D02*
X352431D01*
X332850Y-328126D02*
X337380Y-332655D01*
X359652Y-326856D02*
Y-326841D01*
X352891Y-334811D02*
X359448D01*
X244670Y-330016D02*
X249892Y-324794D01*
X216204Y-361603D02*
X242463Y-335344D01*
X218177Y-376185D02*
X218177D01*
X213579Y-373184D02*
X213579Y-373184D01*
X217308Y-375984D02*
X217520Y-375984D01*
X333628Y-327348D02*
X338157Y-331877D01*
X360480Y-332677D02*
Y-328855D01*
X345229Y-334806D02*
X352886D01*
X213579Y-373184D02*
X214479Y-374084D01*
X251575Y-324097D02*
X325779D01*
X219280Y-376185D02*
X219285Y-376185D01*
X212957Y-371682D02*
Y-369443D01*
X359448Y-334811D02*
X359701Y-334558D01*
X352886Y-334806D02*
X352891Y-334811D01*
X219285Y-376185D02*
X221108D01*
X218177Y-376185D02*
X219280D01*
X214479Y-374084D02*
X215717Y-375322D01*
X244670Y-330016D02*
X244670Y-330016D01*
X267592Y-359055D02*
X365856D01*
X379783Y-348795D02*
Y-348619D01*
X259729Y-362777D02*
X260521Y-361984D01*
X373704Y-355804D02*
X379124Y-350384D01*
X259802Y-366651D02*
Y-364289D01*
X259729Y-364111D02*
Y-362777D01*
X259565Y-367094D02*
X259653Y-367007D01*
X258947Y-362003D02*
X259945Y-361005D01*
X258555Y-366297D02*
X258555Y-366297D01*
X256258Y-374866D02*
X256382D01*
X258946Y-362003D02*
X258947Y-362003D01*
X372927Y-355026D02*
X377940Y-350013D01*
X252650Y-372202D02*
X252652Y-372200D01*
X258555Y-366297D01*
X377658Y-346144D02*
X377940Y-346426D01*
X251793Y-374451D02*
X251794Y-374454D01*
X255668Y-375539D02*
Y-375456D01*
X267307Y-357955D02*
X365856D01*
X252426Y-375861D02*
X252429Y-375863D01*
X258629Y-366120D02*
Y-362771D01*
X372186Y-326020D02*
Y-324364D01*
X388502Y-332095D02*
Y-332095D01*
X272159Y-366037D02*
X273519Y-364676D01*
X388502Y-344983D02*
Y-332095D01*
X371359Y-328019D02*
Y-328019D01*
X272014Y-366323D02*
X272019Y-366318D01*
X371359Y-328034D02*
Y-328019D01*
X273519Y-364676D02*
X273690Y-364505D01*
X272014Y-371248D02*
Y-366323D01*
X382668Y-321663D02*
X385250Y-324246D01*
X278777Y-362598D02*
X370886D01*
X374409Y-320553D02*
X379989D01*
X378735Y-359347D02*
X385250Y-352832D01*
X381890Y-322441D02*
X384473Y-325024D01*
X365198Y-361498D02*
X370886D01*
X270914Y-367564D02*
Y-365867D01*
X374409Y-321654D02*
X379989D01*
X373287Y-326020D02*
Y-324364D01*
X364957Y-361598D02*
X364957Y-361598D01*
X387502Y-344983D02*
Y-332095D01*
X300492Y-361598D02*
X364957D01*
X270914Y-367564D02*
X270914Y-367564D01*
X270914Y-367565D02*
Y-367564D01*
X278362Y-361598D02*
X279527D01*
X377957Y-358570D02*
X385475Y-351051D01*
X374114Y-328019D02*
Y-328019D01*
X270914Y-371505D02*
Y-367565D01*
X374114Y-328034D02*
Y-328019D01*
X270914Y-365867D02*
X272983Y-363798D01*
X227373Y-351990D02*
X232522Y-346841D01*
X227373Y-353050D02*
X227373Y-353050D01*
X227473Y-353150D01*
X226281Y-354080D02*
X226412Y-354211D01*
X225221Y-355141D02*
X225352Y-355271D01*
X224160Y-356201D02*
X224291Y-356332D01*
X223099Y-357262D02*
X223230Y-357393D01*
X222070Y-358354D02*
X222170Y-358453D01*
X219772Y-359591D02*
X221009Y-358354D01*
X300242Y-361598D02*
X300492Y-361598D01*
X285777Y-361598D02*
X300242Y-361598D01*
X285027Y-360848D02*
Y-360848D01*
X283527Y-360848D02*
Y-360848D01*
X282027Y-360848D02*
Y-360848D01*
X280527Y-360848D02*
Y-360848D01*
X279777Y-361598D02*
X279777D01*
X279527D02*
X279777D01*
X253307Y-374555D02*
X253431Y-374431D01*
X253089Y-373994D02*
X253120Y-374075D01*
X253089Y-373994D02*
X253201Y-373459D01*
X255146Y-371514D01*
X256207Y-371514D02*
X256609Y-371916D01*
X257070Y-370256D02*
X257669Y-370855D01*
X258131Y-369196D02*
X258730Y-369795D01*
X259389Y-368332D02*
X259791Y-368734D01*
X259389Y-367271D02*
X259389Y-367271D01*
X259565Y-367094D01*
X259565Y-367094D01*
D17*
X-4953Y-340158D02*
X11045D01*
X-4953Y-349409D02*
Y-340158D01*
X-18601Y-349409D02*
X-4953D01*
X-1181Y-352831D02*
X9843D01*
Y-352756D01*
X-4724Y-283071D02*
X11024D01*
Y-283858D02*
Y-283071D01*
X8479Y-296106D02*
Y-294291D01*
X-23622D02*
X8479D01*
X-23622Y-243307D02*
X10236D01*
Y-242126D01*
X-23622Y-243307D02*
Y-241142D01*
X288Y-229787D02*
X10630D01*
X288Y-234968D02*
Y-229787D01*
X-10630Y-178347D02*
X10794D01*
Y-178576D02*
Y-178347D01*
X-23622Y-192126D02*
X10624D01*
Y-191563D01*
X-23622Y-192126D02*
Y-187992D01*
X38583Y13659D02*
Y16705D01*
X36614Y18674D02*
Y18701D01*
Y18674D02*
X38583Y16705D01*
X36762Y11811D02*
Y11838D01*
X38583Y13659D01*
X38976Y7283D02*
Y9597D01*
X36762Y11811D02*
X38976Y9597D01*
X36614Y4921D02*
X38976Y7283D01*
X38779Y197D02*
Y2756D01*
X36614Y4921D02*
X38779Y2756D01*
X36614Y-1969D02*
X38779Y197D01*
X39370Y-11835D02*
Y-4724D01*
X36614Y-1969D02*
X39370Y-4724D01*
X37032Y-14173D02*
X39370Y-11835D01*
X18898Y-14173D02*
X37032D01*
X12205Y-20866D02*
X18898Y-14173D01*
X-787Y-20866D02*
X12205D01*
X-5118Y-25197D02*
X-787Y-20866D01*
X-6693Y-25197D02*
X-5118D01*
D18*
X473785Y-293027D02*
Y-284414D01*
X480709Y-277490D02*
Y-274456D01*
X482115Y-269853D02*
X486221Y-265748D01*
X482115Y-273050D02*
Y-269853D01*
X480709Y-274456D02*
X482115Y-273050D01*
X473785Y-284414D02*
X480709Y-277490D01*
X473785Y-293027D02*
X475384Y-294626D01*
X479331D01*
D25*
X497441Y-284449D02*
X508719Y-273171D01*
X543724D02*
X547230Y-269665D01*
X508719Y-273171D02*
X543724D01*
X548392Y-269665D02*
X548425Y-269632D01*
X547230Y-269665D02*
X548392D01*
X522047Y-270866D02*
Y-259941D01*
X525984Y-256004D01*
X497441Y-298622D02*
Y-284449D01*
X488931Y-281955D02*
X497572D01*
X511706Y-267822D02*
Y-256109D01*
X497572Y-281955D02*
X511706Y-267822D01*
X497441Y-298622D02*
X503124Y-304305D01*
Y-309017D02*
Y-304305D01*
X501649Y-310492D02*
X503124Y-309017D01*
X496620Y-310492D02*
X501649D01*
X524016Y-243799D02*
X525984Y-245768D01*
Y-256004D02*
Y-245768D01*
X283269Y-169093D02*
X321064D01*
X323622Y-166535D01*
X154263Y-144027D02*
X163468D01*
X150394Y-140157D02*
X154263Y-144027D01*
X394362Y-252245D02*
Y-235924D01*
X364173Y-280315D02*
X366292D01*
X394362Y-252245D01*
X44594Y-126878D02*
X51287D01*
X14961Y-120866D02*
X38583D01*
X44594Y-126878D01*
X13386D02*
Y-122441D01*
X14961Y-120866D01*
X521043Y-199213D02*
X521437Y-198819D01*
X521654D01*
X334815Y-140327D02*
Y-136916D01*
X366583Y-172095D02*
X369224D01*
X334815Y-140327D02*
X366583Y-172095D01*
X163468Y-144027D02*
X187402Y-167961D01*
X363951Y-157258D02*
X392298D01*
X348031Y-149831D02*
X350625Y-152425D01*
X359118D02*
X363951Y-157258D01*
X350625Y-152425D02*
X359118D01*
X309355Y-121302D02*
X312571Y-118085D01*
X348031Y-149831D02*
Y-140086D01*
X312571Y-118085D02*
X335015D01*
X338583Y-121653D01*
Y-130637D02*
Y-121653D01*
Y-130637D02*
X348031Y-140086D01*
X309355Y-154425D02*
Y-121302D01*
X279528Y-162598D02*
X301181D01*
X274016Y-168110D02*
X279528Y-162598D01*
X301181D02*
X309355Y-154425D01*
X230998Y-214014D02*
X280927Y-164085D01*
X303238D02*
X303937Y-163386D01*
X280927Y-164085D02*
X303238D01*
X303937Y-163386D02*
Y-162163D01*
X313036Y-153064D01*
X313471D01*
X310236Y-158268D02*
X312992D01*
X232298Y-214552D02*
X281466Y-165385D01*
X305118D01*
X306299Y-164204D01*
Y-162205D01*
X310236Y-158268D01*
X308374Y-163297D02*
X328225D01*
X282799Y-167201D02*
X307662D01*
X238729Y-211271D02*
X282799Y-167201D01*
X307662D02*
X308374Y-166488D01*
Y-163297D01*
X249897Y-168110D02*
X274016D01*
X227596Y-190411D02*
X249897Y-168110D01*
X191775Y-190411D02*
X227596D01*
X190945Y-189581D02*
X191775Y-190411D01*
X190945Y-189581D02*
Y-166535D01*
X188625Y-164215D02*
X190945Y-166535D01*
X188625Y-164215D02*
Y-141297D01*
X196642Y-133279D01*
X222767D01*
X228209Y-138721D01*
X186847Y-164836D02*
X189155Y-167144D01*
X186847Y-164836D02*
Y-135236D01*
X187402Y-203937D02*
Y-167961D01*
X230998Y-228262D02*
Y-214014D01*
X232298Y-230219D02*
Y-214552D01*
X238729Y-228987D02*
Y-211271D01*
X245064Y-227446D02*
Y-207298D01*
X283269Y-169093D01*
X279848Y-174803D02*
X340265D01*
X248031Y-206619D02*
X279848Y-174803D01*
X248031Y-230315D02*
Y-206619D01*
X279134Y-177559D02*
X311024D01*
X250962Y-229747D02*
Y-205731D01*
X279134Y-177559D01*
X317182Y-119541D02*
X324111D01*
X314567Y-122157D02*
X317182Y-119541D01*
X314567Y-151969D02*
Y-122157D01*
X313471Y-153064D02*
X314567Y-151969D01*
X312992Y-158268D02*
X316142Y-155118D01*
Y-122835D01*
X318135Y-120841D01*
X323203D01*
X337354Y-163297D02*
X341542D01*
X329214Y-162308D02*
X336366D01*
X337354Y-163297D01*
X341542D02*
X343994Y-165748D01*
X328225Y-163297D02*
X329214Y-162308D01*
X302362Y-185433D02*
X313779Y-196850D01*
X319291D01*
X299606Y-185433D02*
X302362D01*
X234449Y-233267D02*
X238729Y-228987D01*
X189155Y-200802D02*
Y-167144D01*
Y-200802D02*
X225525Y-237172D01*
X233300D01*
X234449Y-236023D01*
Y-233267D01*
X233179Y-239764D02*
X233573Y-240158D01*
X235433D01*
X231102Y-239764D02*
X233179D01*
X238247Y-234264D02*
X245064Y-227446D01*
X235433Y-240158D02*
X238247Y-237344D01*
Y-234264D01*
X343994Y-165748D02*
X348031D01*
X228346Y-244882D02*
X233465D01*
X248031Y-230315D01*
X230406Y-250303D02*
X250962Y-229747D01*
X230406Y-251861D02*
Y-250303D01*
X230251Y-232266D02*
X232298Y-230219D01*
X228551Y-230709D02*
X230998Y-228262D01*
X396063Y-190157D02*
X399213Y-193307D01*
X396063Y-190157D02*
Y-161024D01*
X392298Y-157258D02*
X396063Y-161024D01*
X352362Y-185104D02*
X357480Y-190222D01*
Y-200787D02*
Y-190222D01*
X346564Y-181102D02*
X350288D01*
X340265Y-174803D02*
X346564Y-181102D01*
X350288D02*
X352362Y-183177D01*
Y-185104D02*
Y-183177D01*
X357480Y-200787D02*
X359581Y-202888D01*
X373730D01*
X376172Y-211113D02*
X391732Y-226673D01*
X365856Y-191447D02*
X376172Y-201763D01*
Y-211113D02*
Y-201763D01*
X378372Y-210486D02*
X392034Y-224149D01*
X367323Y-186349D02*
X368141Y-187167D01*
X378372Y-210486D02*
Y-194922D01*
X370617Y-187167D02*
X378372Y-194922D01*
X368141Y-187167D02*
X370617D01*
X187402Y-203937D02*
X228346Y-244882D01*
X324111Y-119541D02*
X335827Y-131257D01*
X323203Y-120841D02*
X333190Y-130827D01*
X340828Y-190023D02*
X343701Y-192896D01*
Y-200394D02*
Y-192896D01*
X503051Y-246457D02*
X508268Y-251673D01*
X476772Y-291929D02*
Y-286647D01*
X490551Y-248425D02*
X492520Y-246457D01*
X490551Y-266929D02*
Y-248425D01*
X482776Y-274705D02*
X490551Y-266929D01*
X482776Y-280644D02*
Y-274705D01*
X492520Y-246457D02*
X503051D01*
X476772Y-286647D02*
X482776Y-280644D01*
X506299Y-253937D02*
X509842D01*
X491732Y-275928D02*
Y-270356D01*
X501575Y-249213D02*
X506299Y-253937D01*
X480253Y-292566D02*
X485771Y-298084D01*
X485652Y-282852D02*
Y-282008D01*
X485771Y-298084D02*
X486864D01*
X493203Y-249213D02*
X501575D01*
X485652Y-282008D02*
X491732Y-275928D01*
X486864Y-298084D02*
X492323Y-303543D01*
X492520Y-249896D02*
X493203Y-249213D01*
X480253Y-286103D02*
X483504Y-282852D01*
X514075Y-249705D02*
X522047D01*
X492520Y-269568D02*
Y-249896D01*
X483504Y-282852D02*
X485652D01*
X509842Y-253937D02*
X514075Y-249705D01*
X491732Y-270356D02*
X492520Y-269568D01*
X480253Y-292566D02*
Y-286103D01*
X500125Y-307791D02*
Y-305398D01*
X481765Y-292240D02*
Y-289121D01*
X494065Y-308787D02*
X499129D01*
X500125Y-307791D01*
X491511Y-296784D02*
X500125Y-305398D01*
X481765Y-289121D02*
X488931Y-281955D01*
X466272Y-305118D02*
X469690Y-308536D01*
X481765Y-292240D02*
X486309Y-296784D01*
X461417Y-305118D02*
X466272D01*
X486309Y-296784D02*
X491511D01*
X493814Y-308536D02*
X494065Y-308787D01*
X511706Y-256109D02*
X513386Y-254429D01*
X469690Y-308536D02*
X493814D01*
X470866Y-261811D02*
X473622Y-259055D01*
X470866Y-268110D02*
X476378Y-273622D01*
X470866Y-268110D02*
Y-261811D01*
X473228Y-250787D02*
X482283D01*
X454724Y-308476D02*
Y-289576D01*
X464173Y-259842D02*
X473228Y-250787D01*
X464173Y-280127D02*
Y-259842D01*
X454724Y-289576D02*
X464173Y-280127D01*
X487402Y-256988D02*
Y-255906D01*
X482283Y-250787D02*
X487402Y-255906D01*
X468376Y-260841D02*
X472229Y-256988D01*
X489102Y-245150D02*
X495276Y-238976D01*
X468376Y-269059D02*
Y-260841D01*
X489102Y-257692D02*
Y-245150D01*
X495276Y-238976D02*
X540158D01*
X487345Y-259449D02*
X489102Y-257692D01*
X468376Y-269059D02*
X473303Y-273986D01*
Y-276476D02*
Y-273986D01*
X486036Y-259449D02*
X487345D01*
X483575Y-256988D02*
X486036Y-259449D01*
X472229Y-256988D02*
X483575D01*
X540158Y-238976D02*
X550000Y-248819D01*
Y-255610D02*
Y-248819D01*
X327559Y-146068D02*
X341333Y-159843D01*
X406562Y-224484D02*
Y-221621D01*
X327559Y-146068D02*
Y-141969D01*
X321260Y-135669D02*
X327559Y-141969D01*
X365856Y-191447D02*
Y-181168D01*
X344530Y-159843D02*
X365856Y-181168D01*
X391732Y-226673D02*
X404373D01*
X341333Y-159843D02*
X344530D01*
X404626Y-219685D02*
X406562Y-221621D01*
X404373Y-226673D02*
X406562Y-224484D01*
X331890Y-144882D02*
Y-136299D01*
X321260Y-125669D02*
X331890Y-136299D01*
Y-144882D02*
X367323Y-180315D01*
Y-186349D02*
Y-180315D01*
X392034Y-224149D02*
X404493D01*
X383141Y-211811D02*
X399606D01*
X392596Y-250938D02*
Y-234092D01*
X399606Y-211811D02*
X407948Y-220153D01*
X365581Y-277953D02*
X392596Y-250938D01*
X398341Y-228346D02*
X405118D01*
X341339Y-277953D02*
X365581D01*
X405118Y-228346D02*
X407948Y-225517D01*
X380363Y-209034D02*
X383141Y-211811D01*
X407948Y-225517D02*
Y-220153D01*
X380363Y-209034D02*
Y-196740D01*
X392596Y-234092D02*
X398341Y-228346D01*
X411024Y-225516D02*
Y-213686D01*
X406176Y-230363D02*
X411024Y-225516D01*
X399923Y-230363D02*
X406176D01*
X402278Y-205755D02*
X403092D01*
X394362Y-235924D02*
X399923Y-230363D01*
X403092Y-205755D02*
X411024Y-213686D01*
X394193Y-197670D02*
X402278Y-205755D01*
X277667Y-188583D02*
X280844Y-185406D01*
X305587Y-205512D02*
X344882D01*
X274803Y-188583D02*
X277667D01*
X344882Y-205512D02*
X347638Y-202756D01*
X305118Y-205043D02*
X305587Y-205512D01*
X305118Y-205043D02*
Y-193701D01*
X296824Y-185406D02*
X305118Y-193701D01*
X280844Y-185406D02*
X296824D01*
X298694Y-201843D02*
X306299Y-209449D01*
X298694Y-201843D02*
Y-190107D01*
X293039Y-189639D02*
X298225D01*
X298694Y-190107D01*
X291831Y-190847D02*
X293039Y-189639D01*
X291831Y-197012D02*
Y-190847D01*
X306299Y-209449D02*
X343701D01*
X311024Y-177559D02*
X323488Y-190023D01*
X340828D01*
X228551Y-233505D02*
Y-230709D01*
X382067Y-165250D02*
X382927Y-166110D01*
X376068Y-165250D02*
X382067D01*
X334815Y-136916D02*
X335827Y-135904D01*
Y-131257D01*
X369224Y-172095D02*
X376068Y-165250D01*
X382927Y-167966D02*
Y-166110D01*
Y-167966D02*
X383071Y-168110D01*
X228551Y-233505D02*
X230165Y-235119D01*
X378594Y-172111D02*
Y-166966D01*
X333190Y-141776D02*
X365583Y-174170D01*
X333190Y-141776D02*
Y-130827D01*
X365583Y-174170D02*
X376535D01*
X378594Y-172111D01*
D217*
X321260Y-135669D02*
D03*
Y-125669D02*
D03*
D231*
X530709Y-306299D02*
Y-300787D01*
Y-306299D02*
X533465Y-309055D01*
X555785D01*
X561691Y-303150D02*
X569685D01*
X555785Y-309055D02*
X561691Y-303150D01*
D232*
X373093Y-232972D02*
X382677Y-242556D01*
X381890Y-254331D02*
X382677Y-253543D01*
Y-242556D01*
X368232Y-218526D02*
Y-217717D01*
Y-228111D02*
Y-218526D01*
Y-228111D02*
X373093Y-232972D01*
X361783Y-224975D02*
X368232Y-218526D01*
X344710Y-224975D02*
X361783D01*
X333714Y-235971D02*
X344710Y-224975D01*
X333714Y-239764D02*
Y-235971D01*
X316929Y-269685D02*
X330424Y-256190D01*
X298819Y-269685D02*
X316929D01*
X330424Y-256190D02*
Y-243054D01*
X333714Y-239764D01*
D233*
X230511Y-332333D02*
Y-306577D01*
X213237Y-349606D02*
X230511Y-332333D01*
Y-306577D02*
X238624Y-298463D01*
X158661Y-349606D02*
X213237D01*
D237*
X298031Y-155512D02*
D03*
D244*
X218110Y-163779D02*
D03*
D03*
D249*
X609449Y-148189D02*
D03*
X619449D02*
D03*
D250*
X522047Y-270866D02*
D03*
X496620Y-310492D02*
D03*
X245325Y-120837D02*
D03*
X585039Y-266142D02*
D03*
X560630Y-269291D02*
D03*
X548425Y-269632D02*
D03*
X574406Y-280807D02*
D03*
X323622Y-166535D02*
D03*
X150394Y-140157D02*
D03*
X52501Y-119872D02*
D03*
X44621Y-110628D02*
D03*
X139370Y-118898D02*
D03*
X285384Y-154492D02*
D03*
X282058Y-151217D02*
D03*
X281890Y-155905D02*
D03*
X276083Y-152559D02*
D03*
X255906Y-126378D02*
D03*
Y-131496D02*
D03*
Y-137008D02*
D03*
Y-142126D02*
D03*
X257480Y-150394D02*
D03*
X255512Y-146850D02*
D03*
X140551Y-116535D02*
D03*
X237992Y-374655D02*
D03*
X367422Y-346144D02*
D03*
X241929Y-374655D02*
D03*
X364666Y-346144D02*
D03*
X354036D02*
D03*
X206496Y-374655D02*
D03*
X351280Y-346144D02*
D03*
X210433Y-374655D02*
D03*
X218445Y-374108D02*
D03*
X222638Y-374655D02*
D03*
X359652Y-326841D02*
D03*
X362408D02*
D03*
X521654Y-198819D02*
D03*
X133099Y-136519D02*
D03*
X454775Y-308565D02*
D03*
X569685Y-303150D02*
D03*
X561024Y-183465D02*
D03*
Y-186614D02*
D03*
X-4724Y-283071D02*
D03*
X35433Y-129528D02*
D03*
X32283D02*
D03*
X28740D02*
D03*
X35433Y-50787D02*
D03*
X364173Y-280315D02*
D03*
X505118Y-24016D02*
D03*
X500787Y-24409D02*
D03*
X496457Y-24016D02*
D03*
X505118Y-20079D02*
D03*
X500787D02*
D03*
X496457D02*
D03*
X245669Y-74016D02*
D03*
X246063Y-70079D02*
D03*
X241732Y-74016D02*
D03*
Y-70079D02*
D03*
X326772Y-73622D02*
D03*
X322441D02*
D03*
X317717Y-73228D02*
D03*
X326772Y-69291D02*
D03*
X322441D02*
D03*
X317717D02*
D03*
X295669Y-45276D02*
D03*
X290945D02*
D03*
X295276Y-40945D02*
D03*
X290945D02*
D03*
X295276Y-35433D02*
D03*
X290945D02*
D03*
X118504Y-40945D02*
D03*
X51287Y-126878D02*
D03*
X13386D02*
D03*
X298819Y-269685D02*
D03*
X299606Y-185433D02*
D03*
X231102Y-239764D02*
D03*
X399213Y-193307D02*
D03*
X381890Y-254331D02*
D03*
X343701Y-200394D02*
D03*
X611614Y-186107D02*
D03*
X586221Y-178740D02*
D03*
X586614Y-158661D02*
D03*
X608661Y-220472D02*
D03*
X583858Y-192913D02*
D03*
X341339Y-277953D02*
D03*
X461417Y-305118D02*
D03*
X343701Y-209449D02*
D03*
X347638Y-202756D02*
D03*
X383071Y-168110D02*
D03*
X140116Y-124048D02*
D03*
X189764Y-88189D02*
D03*
X473303Y-276476D02*
D03*
X479331Y-294626D02*
D03*
X487402Y-256988D02*
D03*
X473622Y-259055D02*
D03*
X476378Y-273622D02*
D03*
X486221Y-265748D02*
D03*
X492323Y-303543D02*
D03*
X476772Y-291929D02*
D03*
X404493Y-224149D02*
D03*
X404626Y-219685D02*
D03*
X550000Y-255610D02*
D03*
X522047Y-249705D02*
D03*
X524016Y-243799D02*
D03*
X513386Y-254429D02*
D03*
X508268Y-251673D02*
D03*
X209449Y-72047D02*
D03*
Y-74410D02*
D03*
X101181Y-38583D02*
D03*
X121467Y-74575D02*
D03*
X-18601Y-349409D02*
D03*
X561024Y-340158D02*
D03*
X530709Y-300787D02*
D03*
X530315Y-338976D02*
D03*
X601181Y-23622D02*
D03*
X597244D02*
D03*
Y-29921D02*
D03*
X601181Y-26772D02*
D03*
Y-29921D02*
D03*
X597244Y-26772D02*
D03*
X618110Y-62205D02*
D03*
X544095Y-42126D02*
D03*
X539764D02*
D03*
X534646Y-51968D02*
D03*
X534252Y-48425D02*
D03*
X534646Y-45276D02*
D03*
Y-42126D02*
D03*
X228209Y-138721D02*
D03*
X199193Y-105925D02*
D03*
X130245Y-120870D02*
D03*
X168110Y-100132D02*
D03*
X186847Y-135236D02*
D03*
X39764Y-29528D02*
D03*
Y-25984D02*
D03*
X35731Y-18898D02*
D03*
X47441Y-27362D02*
D03*
Y-21260D02*
D03*
X86614Y-56299D02*
D03*
X91339Y-35039D02*
D03*
X86614Y-39370D02*
D03*
X88583Y-53937D02*
D03*
X85039D02*
D03*
X88583Y-50787D02*
D03*
X85039D02*
D03*
X88583Y-46457D02*
D03*
X85039Y-46850D02*
D03*
X107832Y-10197D02*
D03*
X78740Y18110D02*
D03*
Y15354D02*
D03*
Y9843D02*
D03*
Y6693D02*
D03*
Y3543D02*
D03*
X110589Y1589D02*
D03*
X108268Y394D02*
D03*
X112598D02*
D03*
X388713Y-128731D02*
D03*
X369685Y-123622D02*
D03*
Y-120866D02*
D03*
Y-118110D02*
D03*
X366929Y-123622D02*
D03*
Y-120866D02*
D03*
X363779Y-123622D02*
D03*
X366929Y-118110D02*
D03*
X363779Y-120866D02*
D03*
Y-118110D02*
D03*
X274803Y-188583D02*
D03*
X291831Y-197012D02*
D03*
X333714Y-239764D02*
D03*
X373093Y-232972D02*
D03*
X368232Y-217717D02*
D03*
X415623Y-358391D02*
D03*
X460678Y-359179D02*
D03*
X499525Y-358855D02*
D03*
X543698Y-358659D02*
D03*
X598819Y-343307D02*
D03*
X598959Y-333307D02*
D03*
X378594Y-166966D02*
D03*
X348031Y-165748D02*
D03*
X319291Y-196850D02*
D03*
X373730Y-202888D02*
D03*
X377658Y-346144D02*
D03*
X256890Y-374655D02*
D03*
X380807Y-346144D02*
D03*
X253655Y-374421D02*
D03*
X269502Y-374291D02*
D03*
X273425Y-374655D02*
D03*
X374114Y-328034D02*
D03*
X371359D02*
D03*
X-23622Y-187992D02*
D03*
X-1181Y-352831D02*
D03*
X12598Y-349213D02*
D03*
X14173Y-294320D02*
D03*
X288Y-234968D02*
D03*
X19685Y-239370D02*
D03*
X14665Y-237402D02*
D03*
X13780Y-190551D02*
D03*
X19682Y-192520D02*
D03*
X-10630Y-178347D02*
D03*
X394193Y-197670D02*
D03*
X380363Y-196740D02*
D03*
X157480Y-361811D02*
D03*
X153543Y-358661D02*
D03*
Y-361811D02*
D03*
X155512D02*
D03*
Y-358661D02*
D03*
X157480D02*
D03*
X230165Y-235119D02*
D03*
X230406Y-251861D02*
D03*
X230251Y-232266D02*
D03*
X472047Y-221260D02*
D03*
Y-223228D02*
D03*
Y-219291D02*
D03*
X36614Y18701D02*
D03*
X-23622Y-241142D02*
D03*
Y-294291D02*
D03*
X472047Y-217323D02*
D03*
X36762Y11811D02*
D03*
X36614Y4921D02*
D03*
Y-1969D02*
D03*
D252*
X244670Y-330016D02*
D03*
M02*
